G04 ================== begin FILE IDENTIFICATION RECORD ==================*
G04 Layout Name:  D:/<user>/Wistron_project/16342-2/gbr/16342-2.brd*
G04 Film Name:    BSILK*
G04 File Format:  Gerber RS274X*
G04 File Origin:  Cadence Allegro 16.5-S056*
G04 Origin Date:  Mon Aug 07 11:24:09 2017*
G04 *
G04 Layer:  VIA CLASS/FILMMASKBOTTOM*
G04 Layer:  REF DES/ASSEMBLY_BOTTOM*
G04 Layer:  PACKAGE GEOMETRY/SILKSCREEN_BOTTOM*
G04 Layer:  DRAWING FORMAT/LAYER_PCB_STORY*
G04 Layer:  DRAWING FORMAT/LAYER_SILK_B*
G04 Layer:  BOARD GEOMETRY/SILKSCREEN_BOTTOM*
G04 *
G04 Offset:    (0.00 0.00)*
G04 Mirror:    No*
G04 Mode:      Positive*
G04 Rotation:  0*
G04 FullContactRelief:  No*
G04 UndefLineWidth:     6.00*
G04 ================== end FILE IDENTIFICATION RECORD ====================*
%FSLAX35Y35*MOIN*%
%IR0*IPPOS*OFA0.00000B0.00000*MIA0B0*SFA1.00000B1.00000*%
%ADD10C,.026*%
%ADD11C,.02*%
%ADD12C,.013*%
%ADD13C,.015*%
%ADD14C,.001*%
%ADD15C,.006*%
%ADD16C,.008*%
G75*
%LPD*%
G75*
G36*
G01X195800Y468250D02*
X187800D01*
Y477350D01*
X195800D01*
Y468250D01*
G37*
G36*
G01X305992Y574589D02*
Y583389D01*
X301392D01*
Y574589D01*
X305992D01*
G37*
G36*
G01X694450Y464986D02*
X703250D01*
Y469586D01*
X694450D01*
Y464986D01*
G37*
G36*
G01X810988Y413937D02*
X819788D01*
Y418537D01*
X810988D01*
Y413937D01*
G37*
G54D10*
X60600Y670900D03*
X65900Y671000D03*
X65714Y665850D03*
X60800Y660900D03*
X60700Y665900D03*
X65700Y660900D03*
X139916Y709422D03*
X130019Y709695D03*
X139916Y705822D03*
X130019Y706095D03*
X135019D03*
X70700Y671000D03*
X70800Y660700D03*
X70600Y665800D03*
X139916Y713022D03*
Y716622D03*
Y720222D03*
Y723822D03*
X130019Y713295D03*
Y716895D03*
Y720495D03*
X135019Y710595D03*
Y723595D03*
Y719095D03*
Y714845D03*
X130019Y724095D03*
X311386Y633450D03*
X306300Y638600D03*
X301286Y638650D03*
X301386Y633650D03*
X306286D03*
X311186Y638550D03*
X300720Y704920D03*
X300520Y710020D03*
X290620Y710120D03*
X295634Y710070D03*
X290720Y705120D03*
X295620D03*
X301186Y643650D03*
X306486Y643750D03*
X311286D03*
X300620Y715220D03*
X290520Y715120D03*
X295820Y715220D03*
X365164Y612620D03*
X358864D03*
X371400Y606400D03*
X358800Y606300D03*
X365300Y606500D03*
X371400Y612700D03*
X371300Y618800D03*
X365500Y619000D03*
X358900Y618800D03*
X468000Y31500D03*
Y39500D03*
X464000Y35500D03*
X468000Y35400D03*
X472000Y35500D03*
X603943Y42806D03*
X608143Y42906D03*
X603943Y47006D03*
X608043D03*
X857020Y383172D03*
Y379572D03*
Y386772D03*
X875272Y186265D03*
X878872D03*
X860872D03*
X871672D03*
X868072D03*
X864472D03*
X878372Y191265D03*
X878872Y196265D03*
X864472D03*
X868072D03*
X871672D03*
X875272D03*
X865372Y191265D03*
X873872D03*
X869622D03*
X860872Y196265D03*
Y191265D03*
X871420Y383172D03*
X875020D03*
Y379572D03*
X871420D03*
X867820D03*
X860620D03*
X864220D03*
X875020Y386772D03*
X871420D03*
X867820D03*
X860620D03*
X864220D03*
X867820Y383172D03*
X860620D03*
X864220D03*
G54D11*
G01X-36569Y-23804D02*
Y-103804D01*
G01D02*
X1258031D01*
G01X-40569Y-7804D02*
G02I-12000J0D01*
G01X-45719D02*
G02I-6850J0D01*
G01X-52569Y-23804D02*
Y8196D01*
G01X-36569Y-23804D02*
X1258031D01*
G01X-36569Y-59304D02*
X1258031D01*
G01X-36569Y-7804D02*
X-68569D01*
G01X50300Y588850D02*
Y583850D01*
G01X140324Y548546D02*
X135324D01*
G01X137949Y562749D02*
X132949D01*
G01X96300Y708200D02*
Y703200D01*
G01X187500Y465800D02*
X179800D01*
G01X225701Y514568D02*
X230701D01*
G01X252000Y620300D02*
X247000D01*
G01X321829Y186198D02*
Y181198D01*
G01X313557Y197674D02*
X308557D01*
G01X321905Y194049D02*
Y189049D01*
G01X321263Y224490D02*
X316263D01*
G01X313598Y224515D02*
X308597D01*
G01X326935Y221884D02*
X331935D01*
G01X325100Y237900D02*
Y232900D01*
G01X301392Y573189D02*
X294692D01*
G01X350139Y680369D02*
X340639D01*
G01X470531Y-23804D02*
Y-103804D01*
G01X479843Y37419D02*
X474843D01*
G01X608031Y-23804D02*
Y-103804D01*
G01X661347Y36107D02*
X666347D01*
G01X653347D02*
X658347D01*
G01X689000Y488109D02*
Y493109D01*
G01X674947Y474727D02*
X679947D01*
G01X693050Y469586D02*
Y476286D01*
G01X701865Y514453D02*
X696865D01*
G01X723031Y-23804D02*
Y-103804D01*
G01X752375Y526896D02*
X747375D01*
G01X781739Y526060D02*
X776739D01*
G01X809588Y418537D02*
Y425237D01*
G01X802791Y513268D02*
X797791D01*
G01X890531Y-23804D02*
Y-103804D01*
G01X892126Y198829D02*
Y203829D01*
G01X889301Y206631D02*
Y211631D01*
G01X865445Y214685D02*
Y209685D01*
G01X885786Y273245D02*
Y278245D01*
G01Y297245D02*
Y302245D01*
G01Y305245D02*
Y310245D01*
G01Y289245D02*
Y294245D01*
G01Y281245D02*
Y286245D01*
G01X882114Y400788D02*
Y395788D01*
G01X904190Y401444D02*
X899190D01*
G01X896572Y401425D02*
X891572D01*
G01X869041Y396386D02*
X864041D01*
G01X1060531Y-23804D02*
Y-103804D01*
G01X1258031Y-23804D02*
Y-103804D01*
G01X1286031Y-7804D02*
G02I-12000J0D01*
G01X1280881D02*
G02I-6850J0D01*
G01X1274031Y-23804D02*
Y8196D01*
G01X1290031Y-7804D02*
X1258031D01*
G54D12*
G01X214000Y508080D02*
X211150D01*
Y505380D01*
G01X144400Y503700D02*
Y506550D01*
X141700D01*
G01X326700Y515500D02*
Y518350D01*
X324000D01*
G01X341352Y594753D02*
Y597603D01*
X338652D01*
G01X307100Y600800D02*
Y603650D01*
X304400D01*
G01X369080Y535000D02*
Y537850D01*
X366380D01*
G01X372100Y522700D02*
Y525550D01*
X369400D01*
G54D13*
G01X120197Y74016D02*
Y43308D01*
G01X219213Y433268D02*
X188504D01*
G01X287520Y74016D02*
Y43308D01*
G01X408268Y379088D02*
Y348379D01*
G01Y688303D02*
Y719012D01*
G01X568110Y292684D02*
Y261975D01*
G01Y292684D02*
Y261975D01*
G01Y581748D02*
Y551040D01*
G01X846457Y709449D02*
Y740158D01*
G54D14*
G01X341339Y660579D02*
Y678169D01*
G01X340439D02*
Y660619D01*
G01X340489Y660579D02*
Y678169D01*
G01X340589Y660579D02*
Y678169D01*
G01X340539D02*
Y660619D01*
G01X340689Y660579D02*
Y678169D01*
G01X340639D02*
Y660619D01*
G01X340789Y660579D02*
Y678169D01*
G01X340739D02*
Y660619D01*
G01X340889Y660579D02*
Y678169D01*
G01X340839D02*
Y660619D01*
G01X340989Y660579D02*
Y678169D01*
G01X340939D02*
Y660619D01*
G01X341089Y660579D02*
Y678169D01*
G01X341039D02*
Y660619D01*
G01X341189Y660579D02*
Y678169D01*
G01X341139D02*
Y660619D01*
G01X341289Y660579D02*
Y678169D01*
G01X341239D02*
Y660619D01*
G01X339539Y678169D02*
Y660619D01*
G01X339589Y660579D02*
Y678169D01*
G01X339689Y660579D02*
Y678169D01*
G01X339639D02*
Y660619D01*
G01X339789Y660579D02*
Y678169D01*
G01X339739D02*
Y660619D01*
G01X339889Y660579D02*
Y678169D01*
G01X339839D02*
Y660619D01*
G01X339989Y660579D02*
Y678169D01*
G01X339939D02*
Y660619D01*
G01X340089Y660579D02*
Y678169D01*
G01X340039D02*
Y660619D01*
G01X340189Y660579D02*
Y678169D01*
G01X340139D02*
Y660619D01*
G01X340289Y660579D02*
Y678169D01*
G01X340239D02*
Y660619D01*
G01X340389Y660579D02*
Y678169D01*
G01X340339D02*
Y660619D01*
G01X338639Y678169D02*
Y660619D01*
G01X338689Y660579D02*
Y678169D01*
G01X338789Y660579D02*
Y678169D01*
G01X338739D02*
Y660619D01*
G01X338889Y660579D02*
Y678169D01*
G01X338839D02*
Y660619D01*
G01X338989Y660579D02*
Y678169D01*
G01X338939D02*
Y660619D01*
G01X339089Y660579D02*
Y678169D01*
G01X339039D02*
Y660619D01*
G01X339189Y660579D02*
Y678169D01*
G01X339139D02*
Y660619D01*
G01X339289Y660579D02*
Y678169D01*
G01X339239D02*
Y660619D01*
G01X339389Y660579D02*
Y678169D01*
G01X339339D02*
Y660619D01*
G01X339489Y660579D02*
Y678169D01*
G01X339439D02*
Y660619D01*
G01X337739Y678169D02*
Y660619D01*
G01X337789Y660579D02*
Y678169D01*
G01X337889Y660579D02*
Y678169D01*
G01X337839D02*
Y660619D01*
G01X337989Y660579D02*
Y678169D01*
G01X337939D02*
Y660619D01*
G01X338089Y660579D02*
Y678169D01*
G01X338039D02*
Y660619D01*
G01X338189Y660579D02*
Y678169D01*
G01X338139D02*
Y660619D01*
G01X338289Y660579D02*
Y678169D01*
G01X338239D02*
Y660619D01*
G01X338389Y660579D02*
Y678169D01*
G01X338339D02*
Y660619D01*
G01X338489Y660579D02*
Y678169D01*
G01X338439D02*
Y660619D01*
G01X338589Y660579D02*
Y678169D01*
G01X338539D02*
Y660619D01*
G01X336839Y678169D02*
Y660619D01*
G01X336889Y660579D02*
Y678169D01*
G01X336989Y660579D02*
Y678169D01*
G01X336939D02*
Y660619D01*
G01X337089Y660579D02*
Y678169D01*
G01X337039D02*
Y660619D01*
G01X337189Y660579D02*
Y678169D01*
G01X337139D02*
Y660619D01*
G01X337289Y660579D02*
Y678169D01*
G01X337239D02*
Y660619D01*
G01X337389Y660579D02*
Y678169D01*
G01X337339D02*
Y660619D01*
G01X337489Y660579D02*
Y678169D01*
G01X337439D02*
Y660619D01*
G01X337589Y660579D02*
Y678169D01*
G01X337539D02*
Y660619D01*
G01X337689Y660579D02*
Y678169D01*
G01X337639D02*
Y660619D01*
G01X335939Y678169D02*
Y660619D01*
G01X335989Y660579D02*
Y678169D01*
G01X336089Y660579D02*
Y678169D01*
G01X336039D02*
Y660619D01*
G01X336189Y660579D02*
Y678169D01*
G01X336139D02*
Y660619D01*
G01X336289Y660579D02*
Y678169D01*
G01X336239D02*
Y660619D01*
G01X336389Y660579D02*
Y678169D01*
G01X336339D02*
Y660619D01*
G01X336489Y660579D02*
Y678169D01*
G01X336439D02*
Y660619D01*
G01X336589Y660579D02*
Y678169D01*
G01X336539D02*
Y660619D01*
G01X336689Y660579D02*
Y678169D01*
G01X336639D02*
Y660619D01*
G01X336789Y660579D02*
Y678169D01*
G01X336739D02*
Y660619D01*
G01X335039Y678169D02*
Y660619D01*
G01X335089Y660579D02*
Y678169D01*
G01X335189Y660579D02*
Y678169D01*
G01X335139D02*
Y660619D01*
G01X335289Y660579D02*
Y678169D01*
G01X335239D02*
Y660619D01*
G01X335389Y660579D02*
Y678169D01*
G01X335339D02*
Y660619D01*
G01X335489Y660579D02*
Y678169D01*
G01X335439D02*
Y660619D01*
G01X335589Y660579D02*
Y678169D01*
G01X335539D02*
Y660619D01*
G01X335689Y660579D02*
Y678169D01*
G01X335639D02*
Y660619D01*
G01X335789Y660579D02*
Y678169D01*
G01X335739D02*
Y660619D01*
G01X335889Y660579D02*
Y678169D01*
G01X335839D02*
Y660619D01*
G01X334139Y678169D02*
Y660619D01*
G01X334189Y660579D02*
Y678169D01*
G01X334289Y660579D02*
Y678169D01*
G01X334239D02*
Y660619D01*
G01X334389Y660579D02*
Y678169D01*
G01X334339D02*
Y660619D01*
G01X334489Y660579D02*
Y678169D01*
G01X334439D02*
Y660619D01*
G01X334589Y660579D02*
Y678169D01*
G01X334539D02*
Y660619D01*
G01X334689Y660579D02*
Y678169D01*
G01X334639D02*
Y660619D01*
G01X334789Y660579D02*
Y678169D01*
G01X334739D02*
Y660619D01*
G01X334889Y660579D02*
Y678169D01*
G01X334839D02*
Y660619D01*
G01X334989Y660579D02*
Y678169D01*
G01X334939D02*
Y660619D01*
G01X333239Y678169D02*
Y660619D01*
G01X333289Y660579D02*
Y678169D01*
G01X333389Y660579D02*
Y678169D01*
G01X333339D02*
Y660619D01*
G01X333489Y660579D02*
Y678169D01*
G01X333439D02*
Y660619D01*
G01X333589Y660579D02*
Y678169D01*
G01X333539D02*
Y660619D01*
G01X333689Y660579D02*
Y678169D01*
G01X333639D02*
Y660619D01*
G01X333789Y660579D02*
Y678169D01*
G01X333739D02*
Y660619D01*
G01X333889Y660579D02*
Y678169D01*
G01X333839D02*
Y660619D01*
G01X333989Y660579D02*
Y678169D01*
G01X333939D02*
Y660619D01*
G01X334089Y660579D02*
Y678169D01*
G01X334039D02*
Y660619D01*
G01X332339Y678169D02*
Y660619D01*
G01X332389Y660579D02*
Y678169D01*
G01X332489Y660579D02*
Y678169D01*
G01X332439D02*
Y660619D01*
G01X332589Y660579D02*
Y678169D01*
G01X332539D02*
Y660619D01*
G01X332689Y660579D02*
Y678169D01*
G01X332639D02*
Y660619D01*
G01X332789Y660579D02*
Y678169D01*
G01X332739D02*
Y660619D01*
G01X332889Y660579D02*
Y678169D01*
G01X332839D02*
Y660619D01*
G01X332989Y660579D02*
Y678169D01*
G01X332939D02*
Y660619D01*
G01X333089Y660579D02*
Y678169D01*
G01X333039D02*
Y660619D01*
G01X333189Y660579D02*
Y678169D01*
G01X333139D02*
Y660619D01*
G01X331439Y678169D02*
Y660619D01*
G01X331489Y660579D02*
Y678169D01*
G01X331589Y660579D02*
Y678169D01*
G01X331539D02*
Y660619D01*
G01X331689Y660579D02*
Y678169D01*
G01X331639D02*
Y660619D01*
G01X331789Y660579D02*
Y678169D01*
G01X331739D02*
Y660619D01*
G01X331889Y660579D02*
Y678169D01*
G01X331839D02*
Y660619D01*
G01X331989Y660579D02*
Y678169D01*
G01X331939D02*
Y660619D01*
G01X332089Y660579D02*
Y678169D01*
G01X332039D02*
Y660619D01*
G01X332189Y660579D02*
Y678169D01*
G01X332139D02*
Y660619D01*
G01X332289Y660579D02*
Y678169D01*
G01X332239D02*
Y660619D01*
G01X330539Y678169D02*
Y660619D01*
G01X330589Y660579D02*
Y678169D01*
G01X330689Y660579D02*
Y678169D01*
G01X330639D02*
Y660619D01*
G01X330789Y660579D02*
Y678169D01*
G01X330739D02*
Y660619D01*
G01X330889Y660579D02*
Y678169D01*
G01X330839D02*
Y660619D01*
G01X330989Y660579D02*
Y678169D01*
G01X330939D02*
Y660619D01*
G01X331089Y660579D02*
Y678169D01*
G01X331039D02*
Y660619D01*
G01X331189Y660579D02*
Y678169D01*
G01X331139D02*
Y660619D01*
G01X331289Y660579D02*
Y678169D01*
G01X331239D02*
Y660619D01*
G01X331389Y660579D02*
Y678169D01*
G01X331339D02*
Y660619D01*
G01X329639Y678169D02*
Y660619D01*
G01X329689Y660579D02*
Y678169D01*
G01X329789Y660579D02*
Y678169D01*
G01X329739D02*
Y660619D01*
G01X329889Y660579D02*
Y678169D01*
G01X329839D02*
Y660619D01*
G01X329989Y660579D02*
Y678169D01*
G01X329939D02*
Y660619D01*
G01X330089Y660579D02*
Y678169D01*
G01X330039D02*
Y660619D01*
G01X330189Y660579D02*
Y678169D01*
G01X330139D02*
Y660619D01*
G01X330289Y660579D02*
Y678169D01*
G01X330239D02*
Y660619D01*
G01X330389Y660579D02*
Y678169D01*
G01X330339D02*
Y660619D01*
G01X330489Y660579D02*
Y678169D01*
G01X330439D02*
Y660619D01*
G01X328739Y678169D02*
Y660619D01*
G01X328789Y660579D02*
Y678169D01*
G01X328889Y660579D02*
Y678169D01*
G01X328839D02*
Y660619D01*
G01X328989Y660579D02*
Y678169D01*
G01X328939D02*
Y660619D01*
G01X329089Y660579D02*
Y678169D01*
G01X329039D02*
Y660619D01*
G01X329189Y660579D02*
Y678169D01*
G01X329139D02*
Y660619D01*
G01X329289Y660579D02*
Y678169D01*
G01X329239D02*
Y660619D01*
G01X329389Y660579D02*
Y678169D01*
G01X329339D02*
Y660619D01*
G01X329489Y660579D02*
Y678169D01*
G01X329439D02*
Y660619D01*
G01X329589Y660579D02*
Y678169D01*
G01X329539D02*
Y660619D01*
G01X327839Y678169D02*
Y660619D01*
G01X327889Y660579D02*
Y678169D01*
G01X327989Y660579D02*
Y678169D01*
G01X327939D02*
Y660619D01*
G01X328089Y660579D02*
Y678169D01*
G01X328039D02*
Y660619D01*
G01X328189Y660579D02*
Y678169D01*
G01X328139D02*
Y660619D01*
G01X328289Y660579D02*
Y678169D01*
G01X328239D02*
Y660619D01*
G01X328389Y660579D02*
Y678169D01*
G01X328339D02*
Y660619D01*
G01X328489Y660579D02*
Y678169D01*
G01X328439D02*
Y660619D01*
G01X328589Y660579D02*
Y678169D01*
G01X328539D02*
Y660619D01*
G01X328689Y660579D02*
Y678169D01*
G01X328639D02*
Y660619D01*
G01X327739Y678169D02*
Y660619D01*
G01X327789Y660579D02*
Y678169D01*
G01X327639D02*
Y660619D01*
G01X327689Y660579D02*
Y678169D01*
G01X327539D02*
Y660619D01*
G01X327589Y660579D02*
Y678169D01*
G01X327439D02*
Y660619D01*
G01X327489Y660579D02*
Y678169D01*
G01X327339D02*
Y660619D01*
G01X327389Y660579D02*
Y678169D01*
G01X327239D02*
Y660619D01*
G01X327289Y660579D02*
Y678169D01*
G01X327139D02*
Y660619D01*
G01X327189Y660579D02*
Y678169D01*
G01X327039D02*
Y660619D01*
G01X327089Y660579D02*
Y678169D01*
G01X326989Y660579D02*
Y678169D01*
G01X326939D02*
Y660619D01*
G01X326889Y678169D02*
Y660569D01*
X341389D01*
Y678169D01*
X326889D01*
G54D15*
G01X-9023Y-84471D02*
X-8149Y-83596D01*
X-7494Y-82138D01*
X-7057Y-80095D01*
X-7494Y-78346D01*
X-8367Y-77179D01*
X-9896Y-76304D01*
X-15791D01*
Y-93804D01*
X-8586D01*
X-7057Y-92638D01*
X-6184Y-90887D01*
X-5747Y-88846D01*
X-6184Y-86804D01*
X-7494Y-85054D01*
X-9023Y-84471D01*
X-15791D01*
G01X3674Y-93804D02*
Y-82138D01*
G01Y-84471D02*
X4766Y-83304D01*
X5858Y-82429D01*
X7386Y-82138D01*
X8477Y-82429D01*
X9788Y-83304D01*
G01X19646Y-99054D02*
X20956Y-99637D01*
X22703Y-99054D01*
X23794Y-97888D01*
X24668Y-96429D01*
X25977Y-91763D01*
X28816Y-82138D01*
G01X21829D02*
X25977Y-91763D01*
G01X45224Y-83596D02*
X43696Y-82429D01*
X42386Y-82138D01*
X40639Y-82721D01*
X39329Y-83887D01*
X38456Y-85929D01*
X38237Y-87971D01*
X38456Y-90013D01*
X39329Y-91763D01*
X40639Y-93221D01*
X42386Y-93804D01*
X43914Y-93221D01*
X45224Y-92054D01*
G01X55956Y-85929D02*
X62943D01*
X62288Y-83887D01*
X61196Y-82721D01*
X59668Y-82138D01*
X58139Y-82429D01*
X56829Y-83304D01*
X55956Y-85346D01*
X55519Y-87096D01*
Y-88846D01*
X55956Y-90596D01*
X57048Y-92346D01*
X58358Y-93512D01*
X59886Y-93804D01*
X61414Y-93221D01*
X62943Y-91471D01*
G01X99034Y-77763D02*
X97724Y-76887D01*
X96196Y-76304D01*
X94449D01*
X92484Y-77179D01*
X90956Y-78637D01*
X89864Y-80388D01*
X88991Y-83304D01*
X88772Y-85929D01*
X89209Y-88554D01*
X89864Y-90304D01*
X91174Y-92054D01*
X92703Y-93221D01*
X94231Y-93804D01*
X95759D01*
X97288Y-93221D01*
X98598Y-92346D01*
X99690Y-91180D01*
G01X115661Y-93804D02*
Y-82138D01*
G01Y-84179D02*
X114788Y-83013D01*
X113477Y-82429D01*
X111949Y-82138D01*
X110421Y-82721D01*
X109111Y-83887D01*
X108237Y-85637D01*
X107801Y-87971D01*
X108237Y-90304D01*
X109111Y-92054D01*
X110421Y-93221D01*
X111949Y-93804D01*
X113477Y-93512D01*
X114788Y-92638D01*
X115661Y-91471D01*
G01X125519Y-93804D02*
Y-82138D01*
G01Y-85054D02*
X126393Y-83596D01*
X127703Y-82429D01*
X129449Y-82138D01*
X130977Y-82429D01*
X132288Y-83596D01*
X132943Y-85637D01*
Y-93804D01*
G01X142146Y-99054D02*
X143456Y-99637D01*
X145203Y-99054D01*
X146294Y-97888D01*
X147168Y-96429D01*
X148477Y-91763D01*
X151316Y-82138D01*
G01X144329D02*
X148477Y-91763D01*
G01X164231Y-93804D02*
X162921Y-93512D01*
X161611Y-92346D01*
X160737Y-90304D01*
X160301Y-87971D01*
X160737Y-85637D01*
X161611Y-83596D01*
X162921Y-82429D01*
X164231Y-82138D01*
X165541Y-82429D01*
X166851Y-83596D01*
X167724Y-85637D01*
X167943Y-87971D01*
X167724Y-90304D01*
X166851Y-92346D01*
X165541Y-93512D01*
X164231Y-93804D01*
G01X178019D02*
Y-82138D01*
G01Y-85054D02*
X178893Y-83596D01*
X180203Y-82429D01*
X181949Y-82138D01*
X183477Y-82429D01*
X184788Y-83596D01*
X185443Y-85637D01*
Y-93804D01*
G01X214111Y-76304D02*
X219351D01*
G01X216731D02*
Y-93804D01*
G01X214111D02*
X219351D01*
G01X234231D02*
X232484Y-93512D01*
X230956Y-92346D01*
X229646Y-90596D01*
X228772Y-88554D01*
X228336Y-86221D01*
Y-83887D01*
X228772Y-81554D01*
X229646Y-79512D01*
X230956Y-77763D01*
X232484Y-76596D01*
X234231Y-76304D01*
X235977Y-76596D01*
X237506Y-77763D01*
X238816Y-79512D01*
X239690Y-81554D01*
X240126Y-83887D01*
Y-86221D01*
X239690Y-88554D01*
X238816Y-90596D01*
X237506Y-92346D01*
X235977Y-93512D01*
X234231Y-93804D01*
G01X246054D02*
Y-76304D01*
X251731Y-90887D01*
X257408Y-76304D01*
Y-93804D01*
G01X285639Y-99637D02*
X283456Y-96721D01*
X282364Y-93804D01*
Y-82138D01*
X283456Y-79221D01*
X285639Y-76304D01*
G01X298554Y-93804D02*
Y-76304D01*
X304231Y-90887D01*
X309908Y-76304D01*
Y-93804D01*
G01X321731Y-94387D02*
X321294Y-94096D01*
Y-93512D01*
X321731Y-93221D01*
X322168Y-93512D01*
Y-94096D01*
X321731Y-94387D01*
G01X335083Y-79221D02*
X336393Y-77471D01*
X337921Y-76596D01*
X339668Y-76304D01*
X341851Y-76887D01*
X343379Y-78346D01*
X343816Y-80095D01*
X343598Y-81846D01*
X342724Y-83304D01*
X338358Y-86221D01*
X336393Y-88262D01*
X335083Y-91180D01*
X334646Y-93804D01*
X343816D01*
G01X374231D02*
X372921Y-93512D01*
X371611Y-92346D01*
X370737Y-90304D01*
X370301Y-87971D01*
X370737Y-85637D01*
X371611Y-83596D01*
X372921Y-82429D01*
X374231Y-82138D01*
X375541Y-82429D01*
X376851Y-83596D01*
X377724Y-85637D01*
X377943Y-87971D01*
X377724Y-90304D01*
X376851Y-92346D01*
X375541Y-93512D01*
X374231Y-93804D01*
G01X388019D02*
Y-82138D01*
G01Y-85054D02*
X388893Y-83596D01*
X390203Y-82429D01*
X391949Y-82138D01*
X393477Y-82429D01*
X394788Y-83596D01*
X395443Y-85637D01*
Y-93804D01*
G01X409231D02*
Y-76304D01*
G01X422146Y-99054D02*
X423456Y-99637D01*
X425203Y-99054D01*
X426294Y-97888D01*
X427168Y-96429D01*
X428477Y-91763D01*
X431316Y-82138D01*
G01X424329D02*
X428477Y-91763D01*
G01X445323Y-99637D02*
X447506Y-96721D01*
X448598Y-93804D01*
Y-82138D01*
X447506Y-79221D01*
X445323Y-76304D01*
G01X176054Y-48804D02*
Y-31304D01*
X181731Y-45887D01*
X187408Y-31304D01*
Y-48804D01*
G01X199231D02*
X197921Y-48512D01*
X196611Y-47346D01*
X195737Y-45304D01*
X195301Y-42971D01*
X195737Y-40637D01*
X196611Y-38596D01*
X197921Y-37429D01*
X199231Y-37138D01*
X200541Y-37429D01*
X201851Y-38596D01*
X202724Y-40637D01*
X202943Y-42971D01*
X202724Y-45304D01*
X201851Y-47346D01*
X200541Y-48512D01*
X199231Y-48804D01*
G01X220661Y-31304D02*
Y-48804D01*
G01Y-46180D02*
X219788Y-47638D01*
X218477Y-48512D01*
X216949Y-48804D01*
X215203Y-48221D01*
X213893Y-46763D01*
X213019Y-45013D01*
X212801Y-42971D01*
X213019Y-40929D01*
X213893Y-39179D01*
X215203Y-37721D01*
X216949Y-37138D01*
X218477Y-37429D01*
X219569Y-38013D01*
X220661Y-39179D01*
G01X230956Y-40929D02*
X237943D01*
X237288Y-38887D01*
X236196Y-37721D01*
X234668Y-37138D01*
X233139Y-37429D01*
X231829Y-38304D01*
X230956Y-40346D01*
X230519Y-42096D01*
Y-43846D01*
X230956Y-45596D01*
X232048Y-47346D01*
X233358Y-48512D01*
X234886Y-48804D01*
X236414Y-48221D01*
X237943Y-46471D01*
G01X251731Y-48804D02*
Y-31304D01*
G01X338139Y669369D02*
X330139D01*
G01X334139Y673369D02*
Y665369D01*
G01X504231Y-93804D02*
Y-76304D01*
X501611Y-79804D01*
G01Y-93804D02*
X506851D01*
G01X517583Y-86513D02*
X519111Y-84471D01*
X520421Y-83304D01*
X522168Y-82721D01*
X523696Y-83304D01*
X524788Y-84471D01*
X525661Y-86221D01*
X525879Y-88262D01*
X525661Y-90013D01*
X524788Y-91763D01*
X523477Y-93221D01*
X521949Y-93804D01*
X520203Y-93221D01*
X518674Y-91471D01*
X517801Y-88846D01*
X517583Y-85929D01*
X518019Y-82138D01*
X518674Y-80095D01*
X519766Y-78054D01*
X521294Y-76596D01*
X522823Y-76304D01*
X524351Y-76887D01*
X525443Y-78346D01*
G01X534428Y-90304D02*
X535737Y-92346D01*
X537484Y-93512D01*
X539449Y-93804D01*
X541196Y-93512D01*
X542943Y-92054D01*
X544034Y-90304D01*
X544253Y-88554D01*
X543816Y-86513D01*
X542288Y-85054D01*
X540759Y-84471D01*
X538794D01*
G01X540759D02*
X542069Y-83596D01*
X543161Y-82138D01*
X543598Y-80388D01*
X543161Y-78637D01*
X542069Y-77179D01*
X540104Y-76304D01*
X538139Y-76596D01*
X536174Y-77763D01*
G01X559351Y-93804D02*
Y-76304D01*
X551272Y-88846D01*
X562190D01*
G01X570083Y-79221D02*
X571393Y-77471D01*
X572921Y-76596D01*
X574668Y-76304D01*
X576851Y-76887D01*
X578379Y-78346D01*
X578816Y-80095D01*
X578598Y-81846D01*
X577724Y-83304D01*
X573358Y-86221D01*
X571393Y-88262D01*
X570083Y-91180D01*
X569646Y-93804D01*
X578816D01*
G01X491114Y-48804D02*
Y-31304D01*
X496354D01*
X498101Y-32179D01*
X499411Y-34221D01*
X499848Y-36554D01*
X499411Y-38887D01*
X498319Y-40637D01*
X496354Y-41513D01*
X491114D01*
G01X517784Y-32763D02*
X516474Y-31887D01*
X514946Y-31304D01*
X513199D01*
X511234Y-32179D01*
X509706Y-33637D01*
X508614Y-35388D01*
X507741Y-38304D01*
X507522Y-40929D01*
X507959Y-43554D01*
X508614Y-45304D01*
X509924Y-47054D01*
X511453Y-48221D01*
X512981Y-48804D01*
X514509D01*
X516038Y-48221D01*
X517348Y-47346D01*
X518440Y-46180D01*
G01X532227Y-39471D02*
X533101Y-38596D01*
X533756Y-37138D01*
X534193Y-35095D01*
X533756Y-33346D01*
X532883Y-32179D01*
X531354Y-31304D01*
X525459D01*
Y-48804D01*
X532664D01*
X534193Y-47638D01*
X535066Y-45887D01*
X535503Y-43846D01*
X535066Y-41804D01*
X533756Y-40054D01*
X532227Y-39471D01*
X525459D01*
G01X541431Y-54637D02*
X554531D01*
G01X560459Y-48804D02*
Y-31304D01*
X570503Y-48804D01*
Y-31304D01*
G01X582981Y-48804D02*
X581234Y-48512D01*
X579706Y-47346D01*
X578396Y-45596D01*
X577522Y-43554D01*
X577086Y-41221D01*
Y-38887D01*
X577522Y-36554D01*
X578396Y-34512D01*
X579706Y-32763D01*
X581234Y-31596D01*
X582981Y-31304D01*
X584727Y-31596D01*
X586256Y-32763D01*
X587566Y-34512D01*
X588440Y-36554D01*
X588876Y-38887D01*
Y-41221D01*
X588440Y-43554D01*
X587566Y-45596D01*
X586256Y-47346D01*
X584727Y-48512D01*
X582981Y-48804D01*
G01X633822Y-31304D02*
X639281Y-48804D01*
X644740Y-31304D01*
G01X661148Y-48804D02*
X652414D01*
Y-31304D01*
X661148D01*
G01X657654Y-39762D02*
X652414D01*
G01X669914Y-48804D02*
Y-31304D01*
X675373D01*
X677119Y-32179D01*
X678211Y-33346D01*
X678648Y-35679D01*
X678211Y-38013D01*
X676901Y-39471D01*
X675373Y-40346D01*
X669914D01*
G01X675373D02*
X678648Y-48804D01*
G01X691781Y-49387D02*
X691344Y-49096D01*
Y-48512D01*
X691781Y-48221D01*
X692218Y-48512D01*
Y-49096D01*
X691781Y-49387D01*
G01X661383Y-79221D02*
X662693Y-77471D01*
X664221Y-76596D01*
X665968Y-76304D01*
X668151Y-76887D01*
X669679Y-78346D01*
X670116Y-80095D01*
X669898Y-81846D01*
X669024Y-83304D01*
X664658Y-86221D01*
X662693Y-88262D01*
X661383Y-91180D01*
X660946Y-93804D01*
X670116D01*
G01X839985Y-84471D02*
X839111Y-83596D01*
X838456Y-82138D01*
X838019Y-80095D01*
X838456Y-78346D01*
X839329Y-77179D01*
X840858Y-76304D01*
X846753D01*
Y-93804D01*
X839548D01*
X838019Y-92638D01*
X837146Y-90887D01*
X836709Y-88846D01*
X837146Y-86804D01*
X838456Y-85054D01*
X839985Y-84471D01*
X846753D01*
G01X828816Y-91471D02*
X827069Y-92929D01*
X825104Y-93804D01*
X823358D01*
X821611Y-92929D01*
X820301Y-91471D01*
X819646Y-89429D01*
X820083Y-87388D01*
X821174Y-85637D01*
X823139Y-84471D01*
X825759Y-83887D01*
X827288Y-82721D01*
X827943Y-80679D01*
X827506Y-78637D01*
X826414Y-77179D01*
X824886Y-76304D01*
X823358D01*
X821829Y-76887D01*
X820519Y-78346D01*
G01X809351Y-76304D02*
X804111D01*
G01X806731D02*
Y-93804D01*
G01X809351D02*
X804111D01*
G01X793598Y-76304D02*
Y-93804D01*
X784864D01*
G01X776534D02*
Y-76304D01*
G01X768238D02*
X776534Y-87096D01*
G01X766928Y-93804D02*
X772823Y-82138D01*
G01X767364Y-31304D02*
Y-48804D01*
X776098D01*
G01X793161D02*
Y-37138D01*
G01Y-39179D02*
X792288Y-38013D01*
X790977Y-37429D01*
X789449Y-37138D01*
X787921Y-37721D01*
X786611Y-38887D01*
X785737Y-40637D01*
X785301Y-42971D01*
X785737Y-45304D01*
X786611Y-47054D01*
X787921Y-48221D01*
X789449Y-48804D01*
X790977Y-48512D01*
X792288Y-47638D01*
X793161Y-46471D01*
G01X802146Y-54054D02*
X803456Y-54637D01*
X805203Y-54054D01*
X806294Y-52888D01*
X807168Y-51429D01*
X808477Y-46763D01*
X811316Y-37138D01*
G01X804329D02*
X808477Y-46763D01*
G01X820956Y-40929D02*
X827943D01*
X827288Y-38887D01*
X826196Y-37721D01*
X824668Y-37138D01*
X823139Y-37429D01*
X821829Y-38304D01*
X820956Y-40346D01*
X820519Y-42096D01*
Y-43846D01*
X820956Y-45596D01*
X822048Y-47346D01*
X823358Y-48512D01*
X824886Y-48804D01*
X826414Y-48221D01*
X827943Y-46471D01*
G01X838674Y-48804D02*
Y-37138D01*
G01Y-39471D02*
X839766Y-38304D01*
X840858Y-37429D01*
X842386Y-37138D01*
X843477Y-37429D01*
X844788Y-38304D01*
G01X931781Y-93804D02*
X930034Y-93512D01*
X928506Y-92346D01*
X927196Y-90596D01*
X926322Y-88554D01*
X925886Y-86221D01*
Y-83887D01*
X926322Y-81554D01*
X927196Y-79512D01*
X928506Y-77763D01*
X930034Y-76596D01*
X931781Y-76304D01*
X933527Y-76596D01*
X935056Y-77763D01*
X936366Y-79512D01*
X937240Y-81554D01*
X937676Y-83887D01*
Y-86221D01*
X937240Y-88554D01*
X936366Y-90596D01*
X935056Y-92346D01*
X933527Y-93512D01*
X931781Y-93804D01*
G01X933527Y-89137D02*
X936148Y-93804D01*
G01X944478Y-76304D02*
Y-88846D01*
X945351Y-91471D01*
X947098Y-93221D01*
X949281Y-93804D01*
X951464Y-93221D01*
X953211Y-91471D01*
X954084Y-88846D01*
Y-76304D01*
G01X964161D02*
X969401D01*
G01X966781D02*
Y-93804D01*
G01X964161D02*
X969401D01*
G01X979259D02*
Y-76304D01*
X989303Y-93804D01*
Y-76304D01*
G01X1006584Y-77763D02*
X1005274Y-76887D01*
X1003746Y-76304D01*
X1001999D01*
X1000034Y-77179D01*
X998506Y-78637D01*
X997414Y-80388D01*
X996541Y-83304D01*
X996322Y-85929D01*
X996759Y-88554D01*
X997414Y-90304D01*
X998724Y-92054D01*
X1000253Y-93221D01*
X1001781Y-93804D01*
X1003309D01*
X1004838Y-93221D01*
X1006148Y-92346D01*
X1007240Y-91180D01*
G01X1019281Y-93804D02*
Y-85929D01*
X1014914Y-76304D01*
G01X1023648D02*
X1019281Y-85929D01*
G01X909478Y-48804D02*
Y-31304D01*
X913844D01*
X915591Y-32179D01*
X916901Y-33346D01*
X917993Y-35095D01*
X918866Y-37138D01*
X919084Y-40054D01*
X918866Y-42971D01*
X917993Y-45013D01*
X916901Y-46763D01*
X915591Y-47929D01*
X913844Y-48804D01*
X909478D01*
G01X928506Y-40929D02*
X935493D01*
X934838Y-38887D01*
X933746Y-37721D01*
X932218Y-37138D01*
X930689Y-37429D01*
X929379Y-38304D01*
X928506Y-40346D01*
X928069Y-42096D01*
Y-43846D01*
X928506Y-45596D01*
X929598Y-47346D01*
X930908Y-48512D01*
X932436Y-48804D01*
X933964Y-48221D01*
X935493Y-46471D01*
G01X946006Y-46763D02*
X947098Y-47929D01*
X948626Y-48804D01*
X949936D01*
X951246Y-48221D01*
X952119Y-47346D01*
X952556Y-46180D01*
X952338Y-44429D01*
X951464Y-43554D01*
X947534Y-41804D01*
X946661Y-39762D01*
X947098Y-38304D01*
X947971Y-37429D01*
X949281Y-37138D01*
X950591Y-37429D01*
X951901Y-38304D01*
G01X966781Y-37138D02*
Y-48804D01*
G01Y-32471D02*
X966344Y-32179D01*
Y-31596D01*
X966781Y-31304D01*
X967218Y-31596D01*
Y-32179D01*
X966781Y-32471D01*
G01X981224Y-53179D02*
X982753Y-54346D01*
X984499Y-54637D01*
X986027Y-54346D01*
X987338Y-52888D01*
X988211Y-50846D01*
Y-37138D01*
G01Y-39471D02*
X987338Y-38304D01*
X986027Y-37429D01*
X984499Y-37138D01*
X982753Y-37721D01*
X981661Y-38887D01*
X980787Y-40929D01*
X980351Y-42971D01*
X980569Y-44721D01*
X981443Y-46763D01*
X982753Y-48221D01*
X984499Y-48804D01*
X985809Y-48512D01*
X987338Y-47346D01*
X988211Y-46180D01*
G01X998069Y-48804D02*
Y-37138D01*
G01Y-40054D02*
X998943Y-38596D01*
X1000253Y-37429D01*
X1001999Y-37138D01*
X1003527Y-37429D01*
X1004838Y-38596D01*
X1005493Y-40637D01*
Y-48804D01*
G01X1016006Y-40929D02*
X1022993D01*
X1022338Y-38887D01*
X1021246Y-37721D01*
X1019718Y-37138D01*
X1018189Y-37429D01*
X1016879Y-38304D01*
X1016006Y-40346D01*
X1015569Y-42096D01*
Y-43846D01*
X1016006Y-45596D01*
X1017098Y-47346D01*
X1018408Y-48512D01*
X1019936Y-48804D01*
X1021464Y-48221D01*
X1022993Y-46471D01*
G01X1033724Y-48804D02*
Y-37138D01*
G01Y-39471D02*
X1034816Y-38304D01*
X1035908Y-37429D01*
X1037436Y-37138D01*
X1038527Y-37429D01*
X1039838Y-38304D01*
G01X1080481Y-76304D02*
X1078734Y-76887D01*
X1077424Y-78346D01*
X1076551Y-80095D01*
X1075896Y-82429D01*
X1075678Y-85054D01*
X1075896Y-87679D01*
X1076551Y-90013D01*
X1077424Y-91763D01*
X1078734Y-93221D01*
X1080481Y-93804D01*
X1082227Y-93221D01*
X1083538Y-91763D01*
X1084411Y-90013D01*
X1085066Y-87679D01*
X1085284Y-85054D01*
X1085066Y-82429D01*
X1084411Y-80095D01*
X1083538Y-78346D01*
X1082227Y-76887D01*
X1080481Y-76304D01*
G01X1097981Y-93804D02*
X1099509Y-93512D01*
X1101256Y-92638D01*
X1102348Y-91180D01*
X1102784Y-89137D01*
X1102348Y-87096D01*
X1101038Y-85346D01*
X1099073Y-84471D01*
X1096889D01*
X1095579Y-83887D01*
X1094487Y-82429D01*
X1094051Y-80388D01*
X1094706Y-78346D01*
X1096234Y-76887D01*
X1097981Y-76304D01*
X1099727Y-76887D01*
X1101256Y-78346D01*
X1101911Y-80388D01*
X1101474Y-82429D01*
X1100383Y-83887D01*
X1099073Y-84471D01*
X1096889D01*
X1094924Y-85346D01*
X1093614Y-87096D01*
X1093178Y-89137D01*
X1093614Y-91180D01*
X1094706Y-92638D01*
X1096453Y-93512D01*
X1097981Y-93804D01*
G01X1111551Y-94387D02*
X1119411Y-76304D01*
G01X1132981D02*
X1131234Y-76887D01*
X1129924Y-78346D01*
X1129051Y-80095D01*
X1128396Y-82429D01*
X1128178Y-85054D01*
X1128396Y-87679D01*
X1129051Y-90013D01*
X1129924Y-91763D01*
X1131234Y-93221D01*
X1132981Y-93804D01*
X1134727Y-93221D01*
X1136038Y-91763D01*
X1136911Y-90013D01*
X1137566Y-87679D01*
X1137784Y-85054D01*
X1137566Y-82429D01*
X1136911Y-80095D01*
X1136038Y-78346D01*
X1134727Y-76887D01*
X1132981Y-76304D01*
G01X1150044Y-93804D02*
X1150481Y-90013D01*
X1151136Y-86804D01*
X1152009Y-83887D01*
X1153101Y-80679D01*
X1154848Y-76304D01*
X1146114D01*
G01X1164051Y-94387D02*
X1171911Y-76304D01*
G01X1181333Y-79221D02*
X1182643Y-77471D01*
X1184171Y-76596D01*
X1185918Y-76304D01*
X1188101Y-76887D01*
X1189629Y-78346D01*
X1190066Y-80095D01*
X1189848Y-81846D01*
X1188974Y-83304D01*
X1184608Y-86221D01*
X1182643Y-88262D01*
X1181333Y-91180D01*
X1180896Y-93804D01*
X1190066D01*
G01X1202981Y-76304D02*
X1201234Y-76887D01*
X1199924Y-78346D01*
X1199051Y-80095D01*
X1198396Y-82429D01*
X1198178Y-85054D01*
X1198396Y-87679D01*
X1199051Y-90013D01*
X1199924Y-91763D01*
X1201234Y-93221D01*
X1202981Y-93804D01*
X1204727Y-93221D01*
X1206038Y-91763D01*
X1206911Y-90013D01*
X1207566Y-87679D01*
X1207784Y-85054D01*
X1207566Y-82429D01*
X1206911Y-80095D01*
X1206038Y-78346D01*
X1204727Y-76887D01*
X1202981Y-76304D01*
G01X1220481Y-93804D02*
Y-76304D01*
X1217861Y-79804D01*
G01Y-93804D02*
X1223101D01*
G01X1237544D02*
X1237981Y-90013D01*
X1238636Y-86804D01*
X1239509Y-83887D01*
X1240601Y-80679D01*
X1242348Y-76304D01*
X1233614D01*
G01X1128178Y-48804D02*
Y-31304D01*
X1132544D01*
X1134291Y-32179D01*
X1135601Y-33346D01*
X1136693Y-35095D01*
X1137566Y-37138D01*
X1137784Y-40054D01*
X1137566Y-42971D01*
X1136693Y-45013D01*
X1135601Y-46763D01*
X1134291Y-47929D01*
X1132544Y-48804D01*
X1128178D01*
G01X1154411D02*
Y-37138D01*
G01Y-39179D02*
X1153538Y-38013D01*
X1152227Y-37429D01*
X1150699Y-37138D01*
X1149171Y-37721D01*
X1147861Y-38887D01*
X1146987Y-40637D01*
X1146551Y-42971D01*
X1146987Y-45304D01*
X1147861Y-47054D01*
X1149171Y-48221D01*
X1150699Y-48804D01*
X1152227Y-48512D01*
X1153538Y-47638D01*
X1154411Y-46471D01*
G01X1167981Y-31304D02*
Y-48804D01*
G01X1164924Y-37138D02*
X1171038D01*
G01X1182206Y-40929D02*
X1189193D01*
X1188538Y-38887D01*
X1187446Y-37721D01*
X1185918Y-37138D01*
X1184389Y-37429D01*
X1183079Y-38304D01*
X1182206Y-40346D01*
X1181769Y-42096D01*
Y-43846D01*
X1182206Y-45596D01*
X1183298Y-47346D01*
X1184608Y-48512D01*
X1186136Y-48804D01*
X1187664Y-48221D01*
X1189193Y-46471D01*
G01X47500Y494017D02*
X50000D01*
Y495058D01*
X49875Y495392D01*
X49708Y495600D01*
X49375Y495683D01*
X49042Y495600D01*
X48833Y495350D01*
X48708Y495058D01*
Y494017D01*
G01Y495058D02*
X47500Y495683D01*
G01X49583Y497158D02*
X49833Y497408D01*
X49958Y497700D01*
X50000Y498033D01*
X49917Y498450D01*
X49708Y498742D01*
X49458Y498825D01*
X49208Y498783D01*
X49000Y498617D01*
X48583Y497783D01*
X48292Y497408D01*
X47875Y497158D01*
X47500Y497075D01*
Y498825D01*
G01X48542Y500258D02*
X48833Y500550D01*
X49000Y500800D01*
X49083Y501133D01*
X49000Y501425D01*
X48833Y501633D01*
X48583Y501800D01*
X48292Y501842D01*
X48042Y501800D01*
X47792Y501633D01*
X47583Y501383D01*
X47500Y501092D01*
X47583Y500758D01*
X47833Y500467D01*
X48208Y500300D01*
X48625Y500258D01*
X49167Y500342D01*
X49458Y500467D01*
X49750Y500675D01*
X49958Y500967D01*
X50000Y501258D01*
X49917Y501550D01*
X49708Y501758D01*
G01X50000Y504150D02*
X49917Y503817D01*
X49708Y503567D01*
X49458Y503400D01*
X49125Y503275D01*
X48750Y503233D01*
X48375Y503275D01*
X48042Y503400D01*
X47792Y503567D01*
X47583Y503817D01*
X47500Y504150D01*
X47583Y504483D01*
X47792Y504733D01*
X48042Y504900D01*
X48375Y505025D01*
X48750Y505067D01*
X49125Y505025D01*
X49458Y504900D01*
X49708Y504733D01*
X49917Y504483D01*
X50000Y504150D01*
G01X31000Y494017D02*
X33500D01*
Y495058D01*
X33375Y495392D01*
X33208Y495600D01*
X32875Y495683D01*
X32542Y495600D01*
X32333Y495350D01*
X32208Y495058D01*
Y494017D01*
G01Y495058D02*
X31000Y495683D01*
G01X33083Y497158D02*
X33333Y497408D01*
X33458Y497700D01*
X33500Y498033D01*
X33417Y498450D01*
X33208Y498742D01*
X32958Y498825D01*
X32708Y498783D01*
X32500Y498617D01*
X32083Y497783D01*
X31792Y497408D01*
X31375Y497158D01*
X31000Y497075D01*
Y498825D01*
G01X31375Y500133D02*
X31167Y500383D01*
X31042Y500675D01*
X31000Y501050D01*
X31083Y501425D01*
X31250Y501717D01*
X31542Y501925D01*
X31875Y501967D01*
X32208Y501883D01*
X32417Y501675D01*
X32583Y501383D01*
X32625Y501092D01*
X32583Y500800D01*
X32417Y500425D01*
X33500Y500550D01*
Y501675D01*
G01X31000Y504150D02*
X31042Y504442D01*
X31167Y504775D01*
X31375Y504983D01*
X31667Y505067D01*
X31958Y504983D01*
X32208Y504733D01*
X32333Y504358D01*
Y503942D01*
X32417Y503692D01*
X32625Y503483D01*
X32917Y503400D01*
X33208Y503525D01*
X33417Y503817D01*
X33500Y504150D01*
X33417Y504483D01*
X33208Y504775D01*
X32917Y504900D01*
X32625Y504817D01*
X32417Y504608D01*
X32333Y504358D01*
Y503942D01*
X32208Y503567D01*
X31958Y503317D01*
X31667Y503233D01*
X31375Y503317D01*
X31167Y503525D01*
X31042Y503858D01*
X31000Y504150D01*
G01X43500Y494017D02*
X46000D01*
Y495058D01*
X45875Y495392D01*
X45708Y495600D01*
X45375Y495683D01*
X45042Y495600D01*
X44833Y495350D01*
X44708Y495058D01*
Y494017D01*
G01Y495058D02*
X43500Y495683D01*
G01X45583Y497158D02*
X45833Y497408D01*
X45958Y497700D01*
X46000Y498033D01*
X45917Y498450D01*
X45708Y498742D01*
X45458Y498825D01*
X45208Y498783D01*
X45000Y498617D01*
X44583Y497783D01*
X44292Y497408D01*
X43875Y497158D01*
X43500Y497075D01*
Y498825D01*
G01X43875Y500133D02*
X43667Y500383D01*
X43542Y500675D01*
X43500Y501050D01*
X43583Y501425D01*
X43750Y501717D01*
X44042Y501925D01*
X44375Y501967D01*
X44708Y501883D01*
X44917Y501675D01*
X45083Y501383D01*
X45125Y501092D01*
X45083Y500800D01*
X44917Y500425D01*
X46000Y500550D01*
Y501675D01*
G01X45583Y503358D02*
X45833Y503608D01*
X45958Y503900D01*
X46000Y504233D01*
X45917Y504650D01*
X45708Y504942D01*
X45458Y505025D01*
X45208Y504983D01*
X45000Y504817D01*
X44583Y503983D01*
X44292Y503608D01*
X43875Y503358D01*
X43500Y503275D01*
Y505025D01*
G01X51500Y494017D02*
X54000D01*
Y495058D01*
X53875Y495392D01*
X53708Y495600D01*
X53375Y495683D01*
X53042Y495600D01*
X52833Y495350D01*
X52708Y495058D01*
Y494017D01*
G01Y495058D02*
X51500Y495683D01*
G01X53583Y497158D02*
X53833Y497408D01*
X53958Y497700D01*
X54000Y498033D01*
X53917Y498450D01*
X53708Y498742D01*
X53458Y498825D01*
X53208Y498783D01*
X53000Y498617D01*
X52583Y497783D01*
X52292Y497408D01*
X51875Y497158D01*
X51500Y497075D01*
Y498825D01*
G01Y501550D02*
X54000D01*
X52208Y500008D01*
Y502092D01*
G01X51500Y504150D02*
X51542Y504442D01*
X51667Y504775D01*
X51875Y504983D01*
X52167Y505067D01*
X52458Y504983D01*
X52708Y504733D01*
X52833Y504358D01*
Y503942D01*
X52917Y503692D01*
X53125Y503483D01*
X53417Y503400D01*
X53708Y503525D01*
X53917Y503817D01*
X54000Y504150D01*
X53917Y504483D01*
X53708Y504775D01*
X53417Y504900D01*
X53125Y504817D01*
X52917Y504608D01*
X52833Y504358D01*
Y503942D01*
X52708Y503567D01*
X52458Y503317D01*
X52167Y503233D01*
X51875Y503317D01*
X51667Y503525D01*
X51542Y503858D01*
X51500Y504150D01*
G01X56000Y494017D02*
X58500D01*
Y495058D01*
X58375Y495392D01*
X58208Y495600D01*
X57875Y495683D01*
X57542Y495600D01*
X57333Y495350D01*
X57208Y495058D01*
Y494017D01*
G01Y495058D02*
X56000Y495683D01*
G01X58083Y497158D02*
X58333Y497408D01*
X58458Y497700D01*
X58500Y498033D01*
X58417Y498450D01*
X58208Y498742D01*
X57958Y498825D01*
X57708Y498783D01*
X57500Y498617D01*
X57083Y497783D01*
X56792Y497408D01*
X56375Y497158D01*
X56000Y497075D01*
Y498825D01*
G01Y501550D02*
X58500D01*
X56708Y500008D01*
Y502092D01*
G01X56000Y504650D02*
X58500D01*
X56708Y503108D01*
Y505192D01*
G01X35000Y494017D02*
X37500D01*
Y495058D01*
X37375Y495392D01*
X37208Y495600D01*
X36875Y495683D01*
X36542Y495600D01*
X36333Y495350D01*
X36208Y495058D01*
Y494017D01*
G01Y495058D02*
X35000Y495683D01*
G01X37083Y497158D02*
X37333Y497408D01*
X37458Y497700D01*
X37500Y498033D01*
X37417Y498450D01*
X37208Y498742D01*
X36958Y498825D01*
X36708Y498783D01*
X36500Y498617D01*
X36083Y497783D01*
X35792Y497408D01*
X35375Y497158D01*
X35000Y497075D01*
Y498825D01*
G01Y501550D02*
X37500D01*
X35708Y500008D01*
Y502092D01*
G01X37500Y504150D02*
X37417Y503817D01*
X37208Y503567D01*
X36958Y503400D01*
X36625Y503275D01*
X36250Y503233D01*
X35875Y503275D01*
X35542Y503400D01*
X35292Y503567D01*
X35083Y503817D01*
X35000Y504150D01*
X35083Y504483D01*
X35292Y504733D01*
X35542Y504900D01*
X35875Y505025D01*
X36250Y505067D01*
X36625Y505025D01*
X36958Y504900D01*
X37208Y504733D01*
X37417Y504483D01*
X37500Y504150D01*
G01X39500Y494017D02*
X42000D01*
Y495058D01*
X41875Y495392D01*
X41708Y495600D01*
X41375Y495683D01*
X41042Y495600D01*
X40833Y495350D01*
X40708Y495058D01*
Y494017D01*
G01Y495058D02*
X39500Y495683D01*
G01X41583Y497158D02*
X41833Y497408D01*
X41958Y497700D01*
X42000Y498033D01*
X41917Y498450D01*
X41708Y498742D01*
X41458Y498825D01*
X41208Y498783D01*
X41000Y498617D01*
X40583Y497783D01*
X40292Y497408D01*
X39875Y497158D01*
X39500Y497075D01*
Y498825D01*
G01X40000Y500133D02*
X39708Y500383D01*
X39542Y500717D01*
X39500Y501092D01*
X39542Y501425D01*
X39750Y501758D01*
X40000Y501967D01*
X40250Y502008D01*
X40542Y501925D01*
X40750Y501633D01*
X40833Y501342D01*
Y500967D01*
G01Y501342D02*
X40958Y501592D01*
X41167Y501800D01*
X41417Y501883D01*
X41667Y501800D01*
X41875Y501592D01*
X42000Y501217D01*
X41958Y500842D01*
X41792Y500467D01*
G01X39875Y503233D02*
X39667Y503483D01*
X39542Y503775D01*
X39500Y504150D01*
X39583Y504525D01*
X39750Y504817D01*
X40042Y505025D01*
X40375Y505067D01*
X40708Y504983D01*
X40917Y504775D01*
X41083Y504483D01*
X41125Y504192D01*
X41083Y503900D01*
X40917Y503525D01*
X42000Y503650D01*
Y504775D01*
G01X60592Y546817D02*
X60717Y546567D01*
X60800Y546275D01*
Y545942D01*
X60675Y545567D01*
X60467Y545275D01*
X60217Y545067D01*
X59800Y544900D01*
X59425Y544858D01*
X59050Y544942D01*
X58800Y545067D01*
X58550Y545317D01*
X58383Y545608D01*
X58300Y545900D01*
Y546192D01*
X58383Y546483D01*
X58508Y546733D01*
X58675Y546942D01*
G01X59342Y548208D02*
X59633Y548500D01*
X59800Y548750D01*
X59883Y549083D01*
X59800Y549375D01*
X59633Y549583D01*
X59383Y549750D01*
X59092Y549792D01*
X58842Y549750D01*
X58592Y549583D01*
X58383Y549333D01*
X58300Y549042D01*
X58383Y548708D01*
X58633Y548417D01*
X59008Y548250D01*
X59425Y548208D01*
X59967Y548292D01*
X60258Y548417D01*
X60550Y548625D01*
X60758Y548917D01*
X60800Y549208D01*
X60717Y549500D01*
X60508Y549708D01*
G01X58300Y552100D02*
X58342Y552392D01*
X58467Y552725D01*
X58675Y552933D01*
X58967Y553017D01*
X59258Y552933D01*
X59508Y552683D01*
X59633Y552308D01*
Y551892D01*
X59717Y551642D01*
X59925Y551433D01*
X60217Y551350D01*
X60508Y551475D01*
X60717Y551767D01*
X60800Y552100D01*
X60717Y552433D01*
X60508Y552725D01*
X60217Y552850D01*
X59925Y552767D01*
X59717Y552558D01*
X59633Y552308D01*
Y551892D01*
X59508Y551517D01*
X59258Y551267D01*
X58967Y551183D01*
X58675Y551267D01*
X58467Y551475D01*
X58342Y551808D01*
X58300Y552100D01*
G01X47500Y507017D02*
X50000D01*
Y508058D01*
X49875Y508392D01*
X49708Y508600D01*
X49375Y508683D01*
X49042Y508600D01*
X48833Y508350D01*
X48708Y508058D01*
Y507017D01*
G01Y508058D02*
X47500Y508683D01*
G01X49583Y510158D02*
X49833Y510408D01*
X49958Y510700D01*
X50000Y511033D01*
X49917Y511450D01*
X49708Y511742D01*
X49458Y511825D01*
X49208Y511783D01*
X49000Y511617D01*
X48583Y510783D01*
X48292Y510408D01*
X47875Y510158D01*
X47500Y510075D01*
Y511825D01*
G01X48542Y513258D02*
X48833Y513550D01*
X49000Y513800D01*
X49083Y514133D01*
X49000Y514425D01*
X48833Y514633D01*
X48583Y514800D01*
X48292Y514842D01*
X48042Y514800D01*
X47792Y514633D01*
X47583Y514383D01*
X47500Y514092D01*
X47583Y513758D01*
X47833Y513467D01*
X48208Y513300D01*
X48625Y513258D01*
X49167Y513342D01*
X49458Y513467D01*
X49750Y513675D01*
X49958Y513967D01*
X50000Y514258D01*
X49917Y514550D01*
X49708Y514758D01*
G01X47500Y517150D02*
X50000D01*
X49500Y516650D01*
G01X47500D02*
Y517650D01*
G01X26400Y507217D02*
X28900D01*
Y508258D01*
X28775Y508592D01*
X28608Y508800D01*
X28275Y508883D01*
X27942Y508800D01*
X27733Y508550D01*
X27608Y508258D01*
Y507217D01*
G01Y508258D02*
X26400Y508883D01*
G01X28483Y510358D02*
X28733Y510608D01*
X28858Y510900D01*
X28900Y511233D01*
X28817Y511650D01*
X28608Y511942D01*
X28358Y512025D01*
X28108Y511983D01*
X27900Y511817D01*
X27483Y510983D01*
X27192Y510608D01*
X26775Y510358D01*
X26400Y510275D01*
Y512025D01*
G01X26775Y513333D02*
X26567Y513583D01*
X26442Y513875D01*
X26400Y514250D01*
X26483Y514625D01*
X26650Y514917D01*
X26942Y515125D01*
X27275Y515167D01*
X27608Y515083D01*
X27817Y514875D01*
X27983Y514583D01*
X28025Y514292D01*
X27983Y514000D01*
X27817Y513625D01*
X28900Y513750D01*
Y514875D01*
G01X26692Y516642D02*
X26483Y516933D01*
X26400Y517267D01*
X26483Y517600D01*
X26733Y517892D01*
X27108Y518100D01*
X27483Y518183D01*
X27942D01*
X28317Y518100D01*
X28650Y517892D01*
X28817Y517642D01*
X28900Y517350D01*
X28817Y517017D01*
X28650Y516767D01*
X28400Y516600D01*
X28067Y516517D01*
X27775Y516600D01*
X27483Y516808D01*
X27317Y517058D01*
X27275Y517350D01*
X27358Y517683D01*
X27567Y517933D01*
X27942Y518183D01*
G01X66151Y512077D02*
X62151D01*
Y519477D01*
G01X66251Y504477D02*
X62251D01*
Y511877D01*
G01X34799Y533258D02*
Y535758D01*
X33758D01*
X33424Y535633D01*
X33216Y535466D01*
X33133Y535133D01*
X33216Y534800D01*
X33466Y534591D01*
X33758Y534466D01*
X34799D01*
G01X33758D02*
X33133Y533258D01*
G01X31658Y535341D02*
X31408Y535591D01*
X31116Y535716D01*
X30783Y535758D01*
X30366Y535675D01*
X30074Y535466D01*
X29991Y535216D01*
X30033Y534966D01*
X30199Y534758D01*
X31033Y534341D01*
X31408Y534050D01*
X31658Y533633D01*
X31741Y533258D01*
X29991D01*
G01X28683Y533633D02*
X28433Y533425D01*
X28141Y533300D01*
X27766Y533258D01*
X27391Y533341D01*
X27099Y533508D01*
X26891Y533800D01*
X26849Y534133D01*
X26933Y534466D01*
X27141Y534675D01*
X27433Y534841D01*
X27724Y534883D01*
X28016Y534841D01*
X28391Y534675D01*
X28266Y535758D01*
X27141D01*
G01X24749Y533258D02*
X24666Y533800D01*
X24541Y534258D01*
X24374Y534675D01*
X24166Y535133D01*
X23833Y535758D01*
X25499D01*
G01X43906Y530622D02*
Y534622D01*
X51306D01*
G01X22303Y533643D02*
Y536143D01*
X21262D01*
X20928Y536018D01*
X20720Y535851D01*
X20637Y535518D01*
X20720Y535185D01*
X20970Y534976D01*
X21262Y534851D01*
X22303D01*
G01X21262D02*
X20637Y533643D01*
G01X19162Y535726D02*
X18912Y535976D01*
X18620Y536101D01*
X18287Y536143D01*
X17870Y536060D01*
X17578Y535851D01*
X17495Y535601D01*
X17537Y535351D01*
X17703Y535143D01*
X18537Y534726D01*
X18912Y534435D01*
X19162Y534018D01*
X19245Y533643D01*
X17495D01*
G01X16187Y534018D02*
X15937Y533810D01*
X15645Y533685D01*
X15270Y533643D01*
X14895Y533726D01*
X14603Y533893D01*
X14395Y534185D01*
X14353Y534518D01*
X14437Y534851D01*
X14645Y535060D01*
X14937Y535226D01*
X15228Y535268D01*
X15520Y535226D01*
X15895Y535060D01*
X15770Y536143D01*
X14645D01*
G01X12962Y534685D02*
X12670Y534976D01*
X12420Y535143D01*
X12087Y535226D01*
X11795Y535143D01*
X11587Y534976D01*
X11420Y534726D01*
X11378Y534435D01*
X11420Y534185D01*
X11587Y533935D01*
X11837Y533726D01*
X12128Y533643D01*
X12462Y533726D01*
X12753Y533976D01*
X12920Y534351D01*
X12962Y534768D01*
X12878Y535310D01*
X12753Y535601D01*
X12545Y535893D01*
X12253Y536101D01*
X11962Y536143D01*
X11670Y536060D01*
X11462Y535851D01*
G01X36465Y530638D02*
Y534638D01*
X43865D01*
G01X34799Y552258D02*
Y554758D01*
X33758D01*
X33424Y554633D01*
X33216Y554466D01*
X33133Y554133D01*
X33216Y553800D01*
X33466Y553591D01*
X33758Y553466D01*
X34799D01*
G01X33758D02*
X33133Y552258D01*
G01X31658Y554341D02*
X31408Y554591D01*
X31116Y554716D01*
X30783Y554758D01*
X30366Y554675D01*
X30074Y554466D01*
X29991Y554216D01*
X30033Y553966D01*
X30199Y553758D01*
X31033Y553341D01*
X31408Y553050D01*
X31658Y552633D01*
X31741Y552258D01*
X29991D01*
G01X28683Y552633D02*
X28433Y552425D01*
X28141Y552300D01*
X27766Y552258D01*
X27391Y552341D01*
X27099Y552508D01*
X26891Y552800D01*
X26849Y553133D01*
X26933Y553466D01*
X27141Y553675D01*
X27433Y553841D01*
X27724Y553883D01*
X28016Y553841D01*
X28391Y553675D01*
X28266Y554758D01*
X27141D01*
G01X25583Y552633D02*
X25333Y552425D01*
X25041Y552300D01*
X24666Y552258D01*
X24291Y552341D01*
X23999Y552508D01*
X23791Y552800D01*
X23749Y553133D01*
X23833Y553466D01*
X24041Y553675D01*
X24333Y553841D01*
X24624Y553883D01*
X24916Y553841D01*
X25291Y553675D01*
X25166Y554758D01*
X24041D01*
G01X43985Y553153D02*
Y557153D01*
X51385D01*
G01X22303Y551643D02*
Y554143D01*
X21262D01*
X20928Y554018D01*
X20720Y553851D01*
X20637Y553518D01*
X20720Y553185D01*
X20970Y552976D01*
X21262Y552851D01*
X22303D01*
G01X21262D02*
X20637Y551643D01*
G01X19162Y553726D02*
X18912Y553976D01*
X18620Y554101D01*
X18287Y554143D01*
X17870Y554060D01*
X17578Y553851D01*
X17495Y553601D01*
X17537Y553351D01*
X17703Y553143D01*
X18537Y552726D01*
X18912Y552435D01*
X19162Y552018D01*
X19245Y551643D01*
X17495D01*
G01X16187Y552018D02*
X15937Y551810D01*
X15645Y551685D01*
X15270Y551643D01*
X14895Y551726D01*
X14603Y551893D01*
X14395Y552185D01*
X14353Y552518D01*
X14437Y552851D01*
X14645Y553060D01*
X14937Y553226D01*
X15228Y553268D01*
X15520Y553226D01*
X15895Y553060D01*
X15770Y554143D01*
X14645D01*
G01X11670Y551643D02*
Y554143D01*
X13212Y552351D01*
X11128D01*
G01X36485Y553153D02*
Y557153D01*
X43885D01*
G01X43500Y507017D02*
X46000D01*
Y508058D01*
X45875Y508392D01*
X45708Y508600D01*
X45375Y508683D01*
X45042Y508600D01*
X44833Y508350D01*
X44708Y508058D01*
Y507017D01*
G01Y508058D02*
X43500Y508683D01*
G01X45583Y510158D02*
X45833Y510408D01*
X45958Y510700D01*
X46000Y511033D01*
X45917Y511450D01*
X45708Y511742D01*
X45458Y511825D01*
X45208Y511783D01*
X45000Y511617D01*
X44583Y510783D01*
X44292Y510408D01*
X43875Y510158D01*
X43500Y510075D01*
Y511825D01*
G01X43875Y513133D02*
X43667Y513383D01*
X43542Y513675D01*
X43500Y514050D01*
X43583Y514425D01*
X43750Y514717D01*
X44042Y514925D01*
X44375Y514967D01*
X44708Y514883D01*
X44917Y514675D01*
X45083Y514383D01*
X45125Y514092D01*
X45083Y513800D01*
X44917Y513425D01*
X46000Y513550D01*
Y514675D01*
G01X44000Y516233D02*
X43708Y516483D01*
X43542Y516817D01*
X43500Y517192D01*
X43542Y517525D01*
X43750Y517858D01*
X44000Y518067D01*
X44250Y518108D01*
X44542Y518025D01*
X44750Y517733D01*
X44833Y517442D01*
Y517067D01*
G01Y517442D02*
X44958Y517692D01*
X45167Y517900D01*
X45417Y517983D01*
X45667Y517900D01*
X45875Y517692D01*
X46000Y517317D01*
X45958Y516942D01*
X45792Y516567D01*
G01X34799Y537758D02*
Y540258D01*
X33758D01*
X33424Y540133D01*
X33216Y539966D01*
X33133Y539633D01*
X33216Y539300D01*
X33466Y539091D01*
X33758Y538966D01*
X34799D01*
G01X33758D02*
X33133Y537758D01*
G01X31658Y539841D02*
X31408Y540091D01*
X31116Y540216D01*
X30783Y540258D01*
X30366Y540175D01*
X30074Y539966D01*
X29991Y539716D01*
X30033Y539466D01*
X30199Y539258D01*
X31033Y538841D01*
X31408Y538550D01*
X31658Y538133D01*
X31741Y537758D01*
X29991D01*
G01X28683Y538133D02*
X28433Y537925D01*
X28141Y537800D01*
X27766Y537758D01*
X27391Y537841D01*
X27099Y538008D01*
X26891Y538300D01*
X26849Y538633D01*
X26933Y538966D01*
X27141Y539175D01*
X27433Y539341D01*
X27724Y539383D01*
X28016Y539341D01*
X28391Y539175D01*
X28266Y540258D01*
X27141D01*
G01X24666Y537758D02*
Y540258D01*
X25166Y539758D01*
G01Y537758D02*
X24166D01*
G01X43906Y536249D02*
Y540249D01*
X51306D01*
G01X22303Y538143D02*
Y540643D01*
X21262D01*
X20928Y540518D01*
X20720Y540351D01*
X20637Y540018D01*
X20720Y539685D01*
X20970Y539476D01*
X21262Y539351D01*
X22303D01*
G01X21262D02*
X20637Y538143D01*
G01X19162Y540226D02*
X18912Y540476D01*
X18620Y540601D01*
X18287Y540643D01*
X17870Y540560D01*
X17578Y540351D01*
X17495Y540101D01*
X17537Y539851D01*
X17703Y539643D01*
X18537Y539226D01*
X18912Y538935D01*
X19162Y538518D01*
X19245Y538143D01*
X17495D01*
G01X16187Y538518D02*
X15937Y538310D01*
X15645Y538185D01*
X15270Y538143D01*
X14895Y538226D01*
X14603Y538393D01*
X14395Y538685D01*
X14353Y539018D01*
X14437Y539351D01*
X14645Y539560D01*
X14937Y539726D01*
X15228Y539768D01*
X15520Y539726D01*
X15895Y539560D01*
X15770Y540643D01*
X14645D01*
G01X12170D02*
X12503Y540560D01*
X12753Y540351D01*
X12920Y540101D01*
X13045Y539768D01*
X13087Y539393D01*
X13045Y539018D01*
X12920Y538685D01*
X12753Y538435D01*
X12503Y538226D01*
X12170Y538143D01*
X11837Y538226D01*
X11587Y538435D01*
X11420Y538685D01*
X11295Y539018D01*
X11253Y539393D01*
X11295Y539768D01*
X11420Y540101D01*
X11587Y540351D01*
X11837Y540560D01*
X12170Y540643D01*
G01X36358Y536254D02*
Y540254D01*
X43758D01*
G01X51500Y507017D02*
X54000D01*
Y508058D01*
X53875Y508392D01*
X53708Y508600D01*
X53375Y508683D01*
X53042Y508600D01*
X52833Y508350D01*
X52708Y508058D01*
Y507017D01*
G01Y508058D02*
X51500Y508683D01*
G01X53583Y510158D02*
X53833Y510408D01*
X53958Y510700D01*
X54000Y511033D01*
X53917Y511450D01*
X53708Y511742D01*
X53458Y511825D01*
X53208Y511783D01*
X53000Y511617D01*
X52583Y510783D01*
X52292Y510408D01*
X51875Y510158D01*
X51500Y510075D01*
Y511825D01*
G01Y514550D02*
X54000D01*
X52208Y513008D01*
Y515092D01*
G01X51792Y516442D02*
X51583Y516733D01*
X51500Y517067D01*
X51583Y517400D01*
X51833Y517692D01*
X52208Y517900D01*
X52583Y517983D01*
X53042D01*
X53417Y517900D01*
X53750Y517692D01*
X53917Y517442D01*
X54000Y517150D01*
X53917Y516817D01*
X53750Y516567D01*
X53500Y516400D01*
X53167Y516317D01*
X52875Y516400D01*
X52583Y516608D01*
X52417Y516858D01*
X52375Y517150D01*
X52458Y517483D01*
X52667Y517733D01*
X53042Y517983D01*
G01X34799Y542758D02*
Y545258D01*
X33758D01*
X33424Y545133D01*
X33216Y544966D01*
X33133Y544633D01*
X33216Y544300D01*
X33466Y544091D01*
X33758Y543966D01*
X34799D01*
G01X33758D02*
X33133Y542758D01*
G01X31658Y544841D02*
X31408Y545091D01*
X31116Y545216D01*
X30783Y545258D01*
X30366Y545175D01*
X30074Y544966D01*
X29991Y544716D01*
X30033Y544466D01*
X30199Y544258D01*
X31033Y543841D01*
X31408Y543550D01*
X31658Y543133D01*
X31741Y542758D01*
X29991D01*
G01X27266D02*
Y545258D01*
X28808Y543466D01*
X26724D01*
G01X24749Y542758D02*
X24666Y543300D01*
X24541Y543758D01*
X24374Y544175D01*
X24166Y544633D01*
X23833Y545258D01*
X25499D01*
G01X43906Y541876D02*
Y545876D01*
X51306D01*
G01X22303Y542643D02*
Y545143D01*
X21262D01*
X20928Y545018D01*
X20720Y544851D01*
X20637Y544518D01*
X20720Y544185D01*
X20970Y543976D01*
X21262Y543851D01*
X22303D01*
G01X21262D02*
X20637Y542643D01*
G01X19162Y544726D02*
X18912Y544976D01*
X18620Y545101D01*
X18287Y545143D01*
X17870Y545060D01*
X17578Y544851D01*
X17495Y544601D01*
X17537Y544351D01*
X17703Y544143D01*
X18537Y543726D01*
X18912Y543435D01*
X19162Y543018D01*
X19245Y542643D01*
X17495D01*
G01X14770D02*
Y545143D01*
X16312Y543351D01*
X14228D01*
G01X12962Y543685D02*
X12670Y543976D01*
X12420Y544143D01*
X12087Y544226D01*
X11795Y544143D01*
X11587Y543976D01*
X11420Y543726D01*
X11378Y543435D01*
X11420Y543185D01*
X11587Y542935D01*
X11837Y542726D01*
X12128Y542643D01*
X12462Y542726D01*
X12753Y542976D01*
X12920Y543351D01*
X12962Y543768D01*
X12878Y544310D01*
X12753Y544601D01*
X12545Y544893D01*
X12253Y545101D01*
X11962Y545143D01*
X11670Y545060D01*
X11462Y544851D01*
G01X36458Y541881D02*
Y545881D01*
X43858D01*
G01X55500Y507017D02*
X58000D01*
Y508058D01*
X57875Y508392D01*
X57708Y508600D01*
X57375Y508683D01*
X57042Y508600D01*
X56833Y508350D01*
X56708Y508058D01*
Y507017D01*
G01Y508058D02*
X55500Y508683D01*
G01X57583Y510158D02*
X57833Y510408D01*
X57958Y510700D01*
X58000Y511033D01*
X57917Y511450D01*
X57708Y511742D01*
X57458Y511825D01*
X57208Y511783D01*
X57000Y511617D01*
X56583Y510783D01*
X56292Y510408D01*
X55875Y510158D01*
X55500Y510075D01*
Y511825D01*
G01Y514550D02*
X58000D01*
X56208Y513008D01*
Y515092D01*
G01X55875Y516233D02*
X55667Y516483D01*
X55542Y516775D01*
X55500Y517150D01*
X55583Y517525D01*
X55750Y517817D01*
X56042Y518025D01*
X56375Y518067D01*
X56708Y517983D01*
X56917Y517775D01*
X57083Y517483D01*
X57125Y517192D01*
X57083Y516900D01*
X56917Y516525D01*
X58000Y516650D01*
Y517775D01*
G01X34799Y529258D02*
Y531758D01*
X33758D01*
X33424Y531633D01*
X33216Y531466D01*
X33133Y531133D01*
X33216Y530800D01*
X33466Y530591D01*
X33758Y530466D01*
X34799D01*
G01X33758D02*
X33133Y529258D01*
G01X31658Y531341D02*
X31408Y531591D01*
X31116Y531716D01*
X30783Y531758D01*
X30366Y531675D01*
X30074Y531466D01*
X29991Y531216D01*
X30033Y530966D01*
X30199Y530758D01*
X31033Y530341D01*
X31408Y530050D01*
X31658Y529633D01*
X31741Y529258D01*
X29991D01*
G01X27266D02*
Y531758D01*
X28808Y529966D01*
X26724D01*
G01X25583Y529758D02*
X25333Y529466D01*
X24999Y529300D01*
X24624Y529258D01*
X24291Y529300D01*
X23958Y529508D01*
X23749Y529758D01*
X23708Y530008D01*
X23791Y530300D01*
X24083Y530508D01*
X24374Y530591D01*
X24749D01*
G01X24374D02*
X24124Y530716D01*
X23916Y530925D01*
X23833Y531175D01*
X23916Y531425D01*
X24124Y531633D01*
X24499Y531758D01*
X24874Y531716D01*
X25249Y531550D01*
G01X43906Y524995D02*
Y528995D01*
X51306D01*
G01X22303Y528643D02*
Y531143D01*
X21262D01*
X20928Y531018D01*
X20720Y530851D01*
X20637Y530518D01*
X20720Y530185D01*
X20970Y529976D01*
X21262Y529851D01*
X22303D01*
G01X21262D02*
X20637Y528643D01*
G01X19162Y530726D02*
X18912Y530976D01*
X18620Y531101D01*
X18287Y531143D01*
X17870Y531060D01*
X17578Y530851D01*
X17495Y530601D01*
X17537Y530351D01*
X17703Y530143D01*
X18537Y529726D01*
X18912Y529435D01*
X19162Y529018D01*
X19245Y528643D01*
X17495D01*
G01X14770D02*
Y531143D01*
X16312Y529351D01*
X14228D01*
G01X12962Y530726D02*
X12712Y530976D01*
X12420Y531101D01*
X12087Y531143D01*
X11670Y531060D01*
X11378Y530851D01*
X11295Y530601D01*
X11337Y530351D01*
X11503Y530143D01*
X12337Y529726D01*
X12712Y529435D01*
X12962Y529018D01*
X13045Y528643D01*
X11295D01*
G01X36475Y524995D02*
Y528995D01*
X43875D01*
G01X35000Y507017D02*
X37500D01*
Y508058D01*
X37375Y508392D01*
X37208Y508600D01*
X36875Y508683D01*
X36542Y508600D01*
X36333Y508350D01*
X36208Y508058D01*
Y507017D01*
G01Y508058D02*
X35000Y508683D01*
G01X37083Y510158D02*
X37333Y510408D01*
X37458Y510700D01*
X37500Y511033D01*
X37417Y511450D01*
X37208Y511742D01*
X36958Y511825D01*
X36708Y511783D01*
X36500Y511617D01*
X36083Y510783D01*
X35792Y510408D01*
X35375Y510158D01*
X35000Y510075D01*
Y511825D01*
G01Y514550D02*
X37500D01*
X35708Y513008D01*
Y515092D01*
G01X35000Y517150D02*
X37500D01*
X37000Y516650D01*
G01X35000D02*
Y517650D01*
G01X71778Y512077D02*
X67778D01*
Y519477D01*
G01X71878Y504377D02*
X67878D01*
Y511777D01*
G01X34799Y524258D02*
Y526758D01*
X33758D01*
X33424Y526633D01*
X33216Y526466D01*
X33133Y526133D01*
X33216Y525800D01*
X33466Y525591D01*
X33758Y525466D01*
X34799D01*
G01X33758D02*
X33133Y524258D01*
G01X31658Y526341D02*
X31408Y526591D01*
X31116Y526716D01*
X30783Y526758D01*
X30366Y526675D01*
X30074Y526466D01*
X29991Y526216D01*
X30033Y525966D01*
X30199Y525758D01*
X31033Y525341D01*
X31408Y525050D01*
X31658Y524633D01*
X31741Y524258D01*
X29991D01*
G01X28683Y524758D02*
X28433Y524466D01*
X28099Y524300D01*
X27724Y524258D01*
X27391Y524300D01*
X27058Y524508D01*
X26849Y524758D01*
X26808Y525008D01*
X26891Y525300D01*
X27183Y525508D01*
X27474Y525591D01*
X27849D01*
G01X27474D02*
X27224Y525716D01*
X27016Y525925D01*
X26933Y526175D01*
X27016Y526425D01*
X27224Y526633D01*
X27599Y526758D01*
X27974Y526716D01*
X28349Y526550D01*
G01X24666Y524258D02*
X24374Y524300D01*
X24041Y524425D01*
X23833Y524633D01*
X23749Y524925D01*
X23833Y525216D01*
X24083Y525466D01*
X24458Y525591D01*
X24874D01*
X25124Y525675D01*
X25333Y525883D01*
X25416Y526175D01*
X25291Y526466D01*
X24999Y526675D01*
X24666Y526758D01*
X24333Y526675D01*
X24041Y526466D01*
X23916Y526175D01*
X23999Y525883D01*
X24208Y525675D01*
X24458Y525591D01*
X24874D01*
X25249Y525466D01*
X25499Y525216D01*
X25583Y524925D01*
X25499Y524633D01*
X25291Y524425D01*
X24958Y524300D01*
X24666Y524258D01*
G01X43906Y519269D02*
Y523269D01*
X51306D01*
G01X22303Y524143D02*
Y526643D01*
X21262D01*
X20928Y526518D01*
X20720Y526351D01*
X20637Y526018D01*
X20720Y525685D01*
X20970Y525476D01*
X21262Y525351D01*
X22303D01*
G01X21262D02*
X20637Y524143D01*
G01X19162Y526226D02*
X18912Y526476D01*
X18620Y526601D01*
X18287Y526643D01*
X17870Y526560D01*
X17578Y526351D01*
X17495Y526101D01*
X17537Y525851D01*
X17703Y525643D01*
X18537Y525226D01*
X18912Y524935D01*
X19162Y524518D01*
X19245Y524143D01*
X17495D01*
G01X16187Y524643D02*
X15937Y524351D01*
X15603Y524185D01*
X15228Y524143D01*
X14895Y524185D01*
X14562Y524393D01*
X14353Y524643D01*
X14312Y524893D01*
X14395Y525185D01*
X14687Y525393D01*
X14978Y525476D01*
X15353D01*
G01X14978D02*
X14728Y525601D01*
X14520Y525810D01*
X14437Y526060D01*
X14520Y526310D01*
X14728Y526518D01*
X15103Y526643D01*
X15478Y526601D01*
X15853Y526435D01*
G01X12253Y524143D02*
X12170Y524685D01*
X12045Y525143D01*
X11878Y525560D01*
X11670Y526018D01*
X11337Y526643D01*
X13003D01*
G01X36432Y519271D02*
Y523271D01*
X43832D01*
G01X39000Y507017D02*
X41500D01*
Y508058D01*
X41375Y508392D01*
X41208Y508600D01*
X40875Y508683D01*
X40542Y508600D01*
X40333Y508350D01*
X40208Y508058D01*
Y507017D01*
G01Y508058D02*
X39000Y508683D01*
G01X41083Y510158D02*
X41333Y510408D01*
X41458Y510700D01*
X41500Y511033D01*
X41417Y511450D01*
X41208Y511742D01*
X40958Y511825D01*
X40708Y511783D01*
X40500Y511617D01*
X40083Y510783D01*
X39792Y510408D01*
X39375Y510158D01*
X39000Y510075D01*
Y511825D01*
G01X39500Y513133D02*
X39208Y513383D01*
X39042Y513717D01*
X39000Y514092D01*
X39042Y514425D01*
X39250Y514758D01*
X39500Y514967D01*
X39750Y515008D01*
X40042Y514925D01*
X40250Y514633D01*
X40333Y514342D01*
Y513967D01*
G01Y514342D02*
X40458Y514592D01*
X40667Y514800D01*
X40917Y514883D01*
X41167Y514800D01*
X41375Y514592D01*
X41500Y514217D01*
X41458Y513842D01*
X41292Y513467D01*
G01X40042Y516358D02*
X40333Y516650D01*
X40500Y516900D01*
X40583Y517233D01*
X40500Y517525D01*
X40333Y517733D01*
X40083Y517900D01*
X39792Y517942D01*
X39542Y517900D01*
X39292Y517733D01*
X39083Y517483D01*
X39000Y517192D01*
X39083Y516858D01*
X39333Y516567D01*
X39708Y516400D01*
X40125Y516358D01*
X40667Y516442D01*
X40958Y516567D01*
X41250Y516775D01*
X41458Y517067D01*
X41500Y517358D01*
X41417Y517650D01*
X41208Y517858D01*
G01X34799Y547258D02*
Y549758D01*
X33758D01*
X33424Y549633D01*
X33216Y549466D01*
X33133Y549133D01*
X33216Y548800D01*
X33466Y548591D01*
X33758Y548466D01*
X34799D01*
G01X33758D02*
X33133Y547258D01*
G01X31658Y549341D02*
X31408Y549591D01*
X31116Y549716D01*
X30783Y549758D01*
X30366Y549675D01*
X30074Y549466D01*
X29991Y549216D01*
X30033Y548966D01*
X30199Y548758D01*
X31033Y548341D01*
X31408Y548050D01*
X31658Y547633D01*
X31741Y547258D01*
X29991D01*
G01X28683Y547758D02*
X28433Y547466D01*
X28099Y547300D01*
X27724Y547258D01*
X27391Y547300D01*
X27058Y547508D01*
X26849Y547758D01*
X26808Y548008D01*
X26891Y548300D01*
X27183Y548508D01*
X27474Y548591D01*
X27849D01*
G01X27474D02*
X27224Y548716D01*
X27016Y548925D01*
X26933Y549175D01*
X27016Y549425D01*
X27224Y549633D01*
X27599Y549758D01*
X27974Y549716D01*
X28349Y549550D01*
G01X24166Y547258D02*
Y549758D01*
X25708Y547966D01*
X23624D01*
G01X43985Y547526D02*
Y551526D01*
X51385D01*
G01X22303Y547143D02*
Y549643D01*
X21262D01*
X20928Y549518D01*
X20720Y549351D01*
X20637Y549018D01*
X20720Y548685D01*
X20970Y548476D01*
X21262Y548351D01*
X22303D01*
G01X21262D02*
X20637Y547143D01*
G01X19162Y549226D02*
X18912Y549476D01*
X18620Y549601D01*
X18287Y549643D01*
X17870Y549560D01*
X17578Y549351D01*
X17495Y549101D01*
X17537Y548851D01*
X17703Y548643D01*
X18537Y548226D01*
X18912Y547935D01*
X19162Y547518D01*
X19245Y547143D01*
X17495D01*
G01X16187Y547643D02*
X15937Y547351D01*
X15603Y547185D01*
X15228Y547143D01*
X14895Y547185D01*
X14562Y547393D01*
X14353Y547643D01*
X14312Y547893D01*
X14395Y548185D01*
X14687Y548393D01*
X14978Y548476D01*
X15353D01*
G01X14978D02*
X14728Y548601D01*
X14520Y548810D01*
X14437Y549060D01*
X14520Y549310D01*
X14728Y549518D01*
X15103Y549643D01*
X15478Y549601D01*
X15853Y549435D01*
G01X13087Y547643D02*
X12837Y547351D01*
X12503Y547185D01*
X12128Y547143D01*
X11795Y547185D01*
X11462Y547393D01*
X11253Y547643D01*
X11212Y547893D01*
X11295Y548185D01*
X11587Y548393D01*
X11878Y548476D01*
X12253D01*
G01X11878D02*
X11628Y548601D01*
X11420Y548810D01*
X11337Y549060D01*
X11420Y549310D01*
X11628Y549518D01*
X12003Y549643D01*
X12378Y549601D01*
X12753Y549435D01*
G01X36503Y547508D02*
Y551508D01*
X43903D01*
G01X34799Y556258D02*
Y558758D01*
X33758D01*
X33424Y558633D01*
X33216Y558466D01*
X33133Y558133D01*
X33216Y557800D01*
X33466Y557591D01*
X33758Y557466D01*
X34799D01*
G01X33758D02*
X33133Y556258D01*
G01X31658Y558341D02*
X31408Y558591D01*
X31116Y558716D01*
X30783Y558758D01*
X30366Y558675D01*
X30074Y558466D01*
X29991Y558216D01*
X30033Y557966D01*
X30199Y557758D01*
X31033Y557341D01*
X31408Y557050D01*
X31658Y556633D01*
X31741Y556258D01*
X29991D01*
G01X27766D02*
Y558758D01*
X28266Y558258D01*
G01Y556258D02*
X27266D01*
G01X25458Y558341D02*
X25208Y558591D01*
X24916Y558716D01*
X24583Y558758D01*
X24166Y558675D01*
X23874Y558466D01*
X23791Y558216D01*
X23833Y557966D01*
X23999Y557758D01*
X24833Y557341D01*
X25208Y557050D01*
X25458Y556633D01*
X25541Y556258D01*
X23791D01*
G01X43985Y558879D02*
Y562879D01*
X51385D01*
G01X22303Y556143D02*
Y558643D01*
X21262D01*
X20928Y558518D01*
X20720Y558351D01*
X20637Y558018D01*
X20720Y557685D01*
X20970Y557476D01*
X21262Y557351D01*
X22303D01*
G01X21262D02*
X20637Y556143D01*
G01X19162Y558226D02*
X18912Y558476D01*
X18620Y558601D01*
X18287Y558643D01*
X17870Y558560D01*
X17578Y558351D01*
X17495Y558101D01*
X17537Y557851D01*
X17703Y557643D01*
X18537Y557226D01*
X18912Y556935D01*
X19162Y556518D01*
X19245Y556143D01*
X17495D01*
G01X15270D02*
Y558643D01*
X15770Y558143D01*
G01Y556143D02*
X14770D01*
G01X12170D02*
Y558643D01*
X12670Y558143D01*
G01Y556143D02*
X11670D01*
G01X36400Y558900D02*
Y562900D01*
X43800D01*
G01X33582Y567881D02*
X33832Y568006D01*
X34124Y568089D01*
X34457D01*
X34832Y567964D01*
X35124Y567756D01*
X35332Y567506D01*
X35499Y567089D01*
X35541Y566714D01*
X35457Y566339D01*
X35332Y566089D01*
X35082Y565839D01*
X34791Y565672D01*
X34499Y565589D01*
X34207D01*
X33916Y565672D01*
X33666Y565797D01*
X33457Y565964D01*
G01X32191Y566631D02*
X31899Y566922D01*
X31649Y567089D01*
X31316Y567172D01*
X31024Y567089D01*
X30816Y566922D01*
X30649Y566672D01*
X30607Y566381D01*
X30649Y566131D01*
X30816Y565881D01*
X31066Y565672D01*
X31357Y565589D01*
X31691Y565672D01*
X31982Y565922D01*
X32149Y566297D01*
X32191Y566714D01*
X32107Y567256D01*
X31982Y567547D01*
X31774Y567839D01*
X31482Y568047D01*
X31191Y568089D01*
X30899Y568006D01*
X30691Y567797D01*
G01X29216Y565964D02*
X28966Y565756D01*
X28674Y565631D01*
X28299Y565589D01*
X27924Y565672D01*
X27632Y565839D01*
X27424Y566131D01*
X27382Y566464D01*
X27466Y566797D01*
X27674Y567006D01*
X27966Y567172D01*
X28257Y567214D01*
X28549Y567172D01*
X28924Y567006D01*
X28799Y568089D01*
X27674D01*
G01X47629Y609233D02*
X44296Y616233D01*
X40963Y609233D01*
G01X42163Y611683D02*
X46429D01*
G01X93085Y655819D02*
Y597777D01*
X53585D01*
Y606824D01*
X14980D01*
Y655819D01*
X93085D01*
G01X39270Y587754D02*
X39520Y587879D01*
X39812Y587962D01*
X40145D01*
X40520Y587837D01*
X40812Y587629D01*
X41020Y587379D01*
X41187Y586962D01*
X41229Y586587D01*
X41145Y586212D01*
X41020Y585962D01*
X40770Y585712D01*
X40479Y585545D01*
X40187Y585462D01*
X39895D01*
X39604Y585545D01*
X39354Y585670D01*
X39145Y585837D01*
G01X37879Y586504D02*
X37587Y586795D01*
X37337Y586962D01*
X37004Y587045D01*
X36712Y586962D01*
X36504Y586795D01*
X36337Y586545D01*
X36295Y586254D01*
X36337Y586004D01*
X36504Y585754D01*
X36754Y585545D01*
X37045Y585462D01*
X37379Y585545D01*
X37670Y585795D01*
X37837Y586170D01*
X37879Y586587D01*
X37795Y587129D01*
X37670Y587420D01*
X37462Y587712D01*
X37170Y587920D01*
X36879Y587962D01*
X36587Y587879D01*
X36379Y587670D01*
G01X34904Y585962D02*
X34654Y585670D01*
X34320Y585504D01*
X33945Y585462D01*
X33612Y585504D01*
X33279Y585712D01*
X33070Y585962D01*
X33029Y586212D01*
X33112Y586504D01*
X33404Y586712D01*
X33695Y586795D01*
X34070D01*
G01X33695D02*
X33445Y586920D01*
X33237Y587129D01*
X33154Y587379D01*
X33237Y587629D01*
X33445Y587837D01*
X33820Y587962D01*
X34195Y587920D01*
X34570Y587754D01*
G01X56340Y600126D02*
X58840D01*
Y601167D01*
X58715Y601501D01*
X58548Y601709D01*
X58215Y601792D01*
X57882Y601709D01*
X57673Y601459D01*
X57548Y601167D01*
Y600126D01*
G01Y601167D02*
X56340Y601792D01*
G01X58423Y603267D02*
X58673Y603517D01*
X58798Y603809D01*
X58840Y604142D01*
X58757Y604559D01*
X58548Y604851D01*
X58298Y604934D01*
X58048Y604892D01*
X57840Y604726D01*
X57423Y603892D01*
X57132Y603517D01*
X56715Y603267D01*
X56340Y603184D01*
Y604934D01*
G01Y607076D02*
X56882Y607159D01*
X57340Y607284D01*
X57757Y607451D01*
X58215Y607659D01*
X58840Y607992D01*
Y606326D01*
G01X56840Y609342D02*
X56548Y609592D01*
X56382Y609926D01*
X56340Y610301D01*
X56382Y610634D01*
X56590Y610967D01*
X56840Y611176D01*
X57090Y611217D01*
X57382Y611134D01*
X57590Y610842D01*
X57673Y610551D01*
Y610176D01*
G01Y610551D02*
X57798Y610801D01*
X58007Y611009D01*
X58257Y611092D01*
X58507Y611009D01*
X58715Y610801D01*
X58840Y610426D01*
X58798Y610051D01*
X58632Y609676D01*
G01X60634Y600026D02*
X63134D01*
Y601067D01*
X63009Y601401D01*
X62842Y601609D01*
X62509Y601692D01*
X62176Y601609D01*
X61967Y601359D01*
X61842Y601067D01*
Y600026D01*
G01Y601067D02*
X60634Y601692D01*
G01X62717Y603167D02*
X62967Y603417D01*
X63092Y603709D01*
X63134Y604042D01*
X63051Y604459D01*
X62842Y604751D01*
X62592Y604834D01*
X62342Y604792D01*
X62134Y604626D01*
X61717Y603792D01*
X61426Y603417D01*
X61009Y603167D01*
X60634Y603084D01*
Y604834D01*
G01Y606976D02*
X61176Y607059D01*
X61634Y607184D01*
X62051Y607351D01*
X62509Y607559D01*
X63134Y607892D01*
Y606226D01*
G01X62717Y609367D02*
X62967Y609617D01*
X63092Y609909D01*
X63134Y610242D01*
X63051Y610659D01*
X62842Y610951D01*
X62592Y611034D01*
X62342Y610992D01*
X62134Y610826D01*
X61717Y609992D01*
X61426Y609617D01*
X61009Y609367D01*
X60634Y609284D01*
Y611034D01*
G01X64840Y600126D02*
X67340D01*
Y601167D01*
X67215Y601501D01*
X67048Y601709D01*
X66715Y601792D01*
X66382Y601709D01*
X66173Y601459D01*
X66048Y601167D01*
Y600126D01*
G01Y601167D02*
X64840Y601792D01*
G01Y604059D02*
X67340D01*
X66840Y603559D01*
G01X64840D02*
Y604559D01*
G01Y607159D02*
X64882Y607451D01*
X65007Y607784D01*
X65215Y607992D01*
X65507Y608076D01*
X65798Y607992D01*
X66048Y607742D01*
X66173Y607367D01*
Y606951D01*
X66257Y606701D01*
X66465Y606492D01*
X66757Y606409D01*
X67048Y606534D01*
X67257Y606826D01*
X67340Y607159D01*
X67257Y607492D01*
X67048Y607784D01*
X66757Y607909D01*
X66465Y607826D01*
X66257Y607617D01*
X66173Y607367D01*
Y606951D01*
X66048Y606576D01*
X65798Y606326D01*
X65507Y606242D01*
X65215Y606326D01*
X65007Y606534D01*
X64882Y606867D01*
X64840Y607159D01*
G01X65215Y609342D02*
X65007Y609592D01*
X64882Y609884D01*
X64840Y610259D01*
X64923Y610634D01*
X65090Y610926D01*
X65382Y611134D01*
X65715Y611176D01*
X66048Y611092D01*
X66257Y610884D01*
X66423Y610592D01*
X66465Y610301D01*
X66423Y610009D01*
X66257Y609634D01*
X67340Y609759D01*
Y610884D01*
G01X60356Y635170D02*
Y637670D01*
X59315D01*
X58981Y637545D01*
X58773Y637378D01*
X58690Y637045D01*
X58773Y636712D01*
X59023Y636503D01*
X59315Y636378D01*
X60356D01*
G01X59315D02*
X58690Y635170D01*
G01X57340Y635670D02*
X57090Y635378D01*
X56756Y635212D01*
X56381Y635170D01*
X56048Y635212D01*
X55715Y635420D01*
X55506Y635670D01*
X55465Y635920D01*
X55548Y636212D01*
X55840Y636420D01*
X56131Y636503D01*
X56506D01*
G01X56131D02*
X55881Y636628D01*
X55673Y636837D01*
X55590Y637087D01*
X55673Y637337D01*
X55881Y637545D01*
X56256Y637670D01*
X56631Y637628D01*
X57006Y637462D01*
G01X54115Y636212D02*
X53823Y636503D01*
X53573Y636670D01*
X53240Y636753D01*
X52948Y636670D01*
X52740Y636503D01*
X52573Y636253D01*
X52531Y635962D01*
X52573Y635712D01*
X52740Y635462D01*
X52990Y635253D01*
X53281Y635170D01*
X53615Y635253D01*
X53906Y635503D01*
X54073Y635878D01*
X54115Y636295D01*
X54031Y636837D01*
X53906Y637128D01*
X53698Y637420D01*
X53406Y637628D01*
X53115Y637670D01*
X52823Y637587D01*
X52615Y637378D01*
G01X50223Y635170D02*
Y637670D01*
X50723Y637170D01*
G01Y635170D02*
X49723D01*
G01X59356Y630709D02*
Y633209D01*
X58315D01*
X57981Y633084D01*
X57773Y632917D01*
X57690Y632584D01*
X57773Y632251D01*
X58023Y632042D01*
X58315Y631917D01*
X59356D01*
G01X58315D02*
X57690Y630709D01*
G01X56340Y631209D02*
X56090Y630917D01*
X55756Y630751D01*
X55381Y630709D01*
X55048Y630751D01*
X54715Y630959D01*
X54506Y631209D01*
X54465Y631459D01*
X54548Y631751D01*
X54840Y631959D01*
X55131Y632042D01*
X55506D01*
G01X55131D02*
X54881Y632167D01*
X54673Y632376D01*
X54590Y632626D01*
X54673Y632876D01*
X54881Y633084D01*
X55256Y633209D01*
X55631Y633167D01*
X56006Y633001D01*
G01X53240Y631084D02*
X52990Y630876D01*
X52698Y630751D01*
X52323Y630709D01*
X51948Y630792D01*
X51656Y630959D01*
X51448Y631251D01*
X51406Y631584D01*
X51490Y631917D01*
X51698Y632126D01*
X51990Y632292D01*
X52281Y632334D01*
X52573Y632292D01*
X52948Y632126D01*
X52823Y633209D01*
X51698D01*
G01X49223Y630709D02*
X48931Y630751D01*
X48598Y630876D01*
X48390Y631084D01*
X48306Y631376D01*
X48390Y631667D01*
X48640Y631917D01*
X49015Y632042D01*
X49431D01*
X49681Y632126D01*
X49890Y632334D01*
X49973Y632626D01*
X49848Y632917D01*
X49556Y633126D01*
X49223Y633209D01*
X48890Y633126D01*
X48598Y632917D01*
X48473Y632626D01*
X48556Y632334D01*
X48765Y632126D01*
X49015Y632042D01*
X49431D01*
X49806Y631917D01*
X50056Y631667D01*
X50140Y631376D01*
X50056Y631084D01*
X49848Y630876D01*
X49515Y630751D01*
X49223Y630709D01*
G01X72586Y632302D02*
Y634802D01*
X71545D01*
X71211Y634677D01*
X71003Y634510D01*
X70920Y634177D01*
X71003Y633844D01*
X71253Y633635D01*
X71545Y633510D01*
X72586D01*
G01X71545D02*
X70920Y632302D01*
G01X68653D02*
Y634802D01*
X69153Y634302D01*
G01Y632302D02*
X68153D01*
G01X66345Y633344D02*
X66053Y633635D01*
X65803Y633802D01*
X65470Y633885D01*
X65178Y633802D01*
X64970Y633635D01*
X64803Y633385D01*
X64761Y633094D01*
X64803Y632844D01*
X64970Y632594D01*
X65220Y632385D01*
X65511Y632302D01*
X65845Y632385D01*
X66136Y632635D01*
X66303Y633010D01*
X66345Y633427D01*
X66261Y633969D01*
X66136Y634260D01*
X65928Y634552D01*
X65636Y634760D01*
X65345Y634802D01*
X65053Y634719D01*
X64845Y634510D01*
G01X63370Y632677D02*
X63120Y632469D01*
X62828Y632344D01*
X62453Y632302D01*
X62078Y632385D01*
X61786Y632552D01*
X61578Y632844D01*
X61536Y633177D01*
X61620Y633510D01*
X61828Y633719D01*
X62120Y633885D01*
X62411Y633927D01*
X62703Y633885D01*
X63078Y633719D01*
X62953Y634802D01*
X61828D01*
G01X75056Y637270D02*
Y639770D01*
X74015D01*
X73681Y639645D01*
X73473Y639478D01*
X73390Y639145D01*
X73473Y638812D01*
X73723Y638603D01*
X74015Y638478D01*
X75056D01*
G01X74015D02*
X73390Y637270D01*
G01X71123D02*
Y639770D01*
X71623Y639270D01*
G01Y637270D02*
X70623D01*
G01X68815Y638312D02*
X68523Y638603D01*
X68273Y638770D01*
X67940Y638853D01*
X67648Y638770D01*
X67440Y638603D01*
X67273Y638353D01*
X67231Y638062D01*
X67273Y637812D01*
X67440Y637562D01*
X67690Y637353D01*
X67981Y637270D01*
X68315Y637353D01*
X68606Y637603D01*
X68773Y637978D01*
X68815Y638395D01*
X68731Y638937D01*
X68606Y639228D01*
X68398Y639520D01*
X68106Y639728D01*
X67815Y639770D01*
X67523Y639687D01*
X67315Y639478D01*
G01X65840Y637770D02*
X65590Y637478D01*
X65256Y637312D01*
X64881Y637270D01*
X64548Y637312D01*
X64215Y637520D01*
X64006Y637770D01*
X63965Y638020D01*
X64048Y638312D01*
X64340Y638520D01*
X64631Y638603D01*
X65006D01*
G01X64631D02*
X64381Y638728D01*
X64173Y638937D01*
X64090Y639187D01*
X64173Y639437D01*
X64381Y639645D01*
X64756Y639770D01*
X65131Y639728D01*
X65506Y639562D01*
G01X72356Y628209D02*
Y630709D01*
X71315D01*
X70981Y630584D01*
X70773Y630417D01*
X70690Y630084D01*
X70773Y629751D01*
X71023Y629542D01*
X71315Y629417D01*
X72356D01*
G01X71315D02*
X70690Y628209D01*
G01X68423D02*
Y630709D01*
X68923Y630209D01*
G01Y628209D02*
X67923D01*
G01X66240Y628584D02*
X65990Y628376D01*
X65698Y628251D01*
X65323Y628209D01*
X64948Y628292D01*
X64656Y628459D01*
X64448Y628751D01*
X64406Y629084D01*
X64490Y629417D01*
X64698Y629626D01*
X64990Y629792D01*
X65281Y629834D01*
X65573Y629792D01*
X65948Y629626D01*
X65823Y630709D01*
X64698D01*
G01X63140Y628709D02*
X62890Y628417D01*
X62556Y628251D01*
X62181Y628209D01*
X61848Y628251D01*
X61515Y628459D01*
X61306Y628709D01*
X61265Y628959D01*
X61348Y629251D01*
X61640Y629459D01*
X61931Y629542D01*
X62306D01*
G01X61931D02*
X61681Y629667D01*
X61473Y629876D01*
X61390Y630126D01*
X61473Y630376D01*
X61681Y630584D01*
X62056Y630709D01*
X62431Y630667D01*
X62806Y630501D01*
G01X67876Y623791D02*
Y626291D01*
X66835D01*
X66501Y626166D01*
X66293Y625999D01*
X66210Y625666D01*
X66293Y625333D01*
X66543Y625124D01*
X66835Y624999D01*
X67876D01*
G01X66835D02*
X66210Y623791D01*
G01X63943D02*
Y626291D01*
X64443Y625791D01*
G01Y623791D02*
X63443D01*
G01X61760Y624166D02*
X61510Y623958D01*
X61218Y623833D01*
X60843Y623791D01*
X60468Y623874D01*
X60176Y624041D01*
X59968Y624333D01*
X59926Y624666D01*
X60010Y624999D01*
X60218Y625208D01*
X60510Y625374D01*
X60801Y625416D01*
X61093Y625374D01*
X61468Y625208D01*
X61343Y626291D01*
X60218D01*
G01X57743Y623791D02*
Y626291D01*
X58243Y625791D01*
G01Y623791D02*
X57243D01*
G01X67356Y616709D02*
Y619209D01*
X66315D01*
X65981Y619084D01*
X65773Y618917D01*
X65690Y618584D01*
X65773Y618251D01*
X66023Y618042D01*
X66315Y617917D01*
X67356D01*
G01X66315D02*
X65690Y616709D01*
G01X63423D02*
Y619209D01*
X63923Y618709D01*
G01Y616709D02*
X62923D01*
G01X60406D02*
X60323Y617251D01*
X60198Y617709D01*
X60031Y618126D01*
X59823Y618584D01*
X59490Y619209D01*
X61156D01*
G01X58015Y617751D02*
X57723Y618042D01*
X57473Y618209D01*
X57140Y618292D01*
X56848Y618209D01*
X56640Y618042D01*
X56473Y617792D01*
X56431Y617501D01*
X56473Y617251D01*
X56640Y617001D01*
X56890Y616792D01*
X57181Y616709D01*
X57515Y616792D01*
X57806Y617042D01*
X57973Y617417D01*
X58015Y617834D01*
X57931Y618376D01*
X57806Y618667D01*
X57598Y618959D01*
X57306Y619167D01*
X57015Y619209D01*
X56723Y619126D01*
X56515Y618917D01*
G01X67656Y612776D02*
Y615276D01*
X66615D01*
X66281Y615151D01*
X66073Y614984D01*
X65990Y614651D01*
X66073Y614318D01*
X66323Y614109D01*
X66615Y613984D01*
X67656D01*
G01X66615D02*
X65990Y612776D01*
G01X63723D02*
Y615276D01*
X64223Y614776D01*
G01Y612776D02*
X63223D01*
G01X60706D02*
X60623Y613318D01*
X60498Y613776D01*
X60331Y614193D01*
X60123Y614651D01*
X59790Y615276D01*
X61456D01*
G01X58440Y613151D02*
X58190Y612943D01*
X57898Y612818D01*
X57523Y612776D01*
X57148Y612859D01*
X56856Y613026D01*
X56648Y613318D01*
X56606Y613651D01*
X56690Y613984D01*
X56898Y614193D01*
X57190Y614359D01*
X57481Y614401D01*
X57773Y614359D01*
X58148Y614193D01*
X58023Y615276D01*
X56898D01*
G01X34720Y576862D02*
Y579362D01*
X33679D01*
X33345Y579237D01*
X33137Y579070D01*
X33054Y578737D01*
X33137Y578404D01*
X33387Y578195D01*
X33679Y578070D01*
X34720D01*
G01X33679D02*
X33054Y576862D01*
G01X31579Y578945D02*
X31329Y579195D01*
X31037Y579320D01*
X30704Y579362D01*
X30287Y579279D01*
X29995Y579070D01*
X29912Y578820D01*
X29954Y578570D01*
X30120Y578362D01*
X30954Y577945D01*
X31329Y577654D01*
X31579Y577237D01*
X31662Y576862D01*
X29912D01*
G01X27687D02*
Y579362D01*
X28187Y578862D01*
G01Y576862D02*
X27187D01*
G01X24587Y579362D02*
X24920Y579279D01*
X25170Y579070D01*
X25337Y578820D01*
X25462Y578487D01*
X25504Y578112D01*
X25462Y577737D01*
X25337Y577404D01*
X25170Y577154D01*
X24920Y576945D01*
X24587Y576862D01*
X24254Y576945D01*
X24004Y577154D01*
X23837Y577404D01*
X23712Y577737D01*
X23670Y578112D01*
X23712Y578487D01*
X23837Y578820D01*
X24004Y579070D01*
X24254Y579279D01*
X24587Y579362D01*
G01X53100Y573850D02*
Y577850D01*
X60500D01*
G01X34725Y572924D02*
Y575424D01*
X33684D01*
X33350Y575299D01*
X33142Y575132D01*
X33059Y574799D01*
X33142Y574466D01*
X33392Y574257D01*
X33684Y574132D01*
X34725D01*
G01X33684D02*
X33059Y572924D01*
G01X31584Y575007D02*
X31334Y575257D01*
X31042Y575382D01*
X30709Y575424D01*
X30292Y575341D01*
X30000Y575132D01*
X29917Y574882D01*
X29959Y574632D01*
X30125Y574424D01*
X30959Y574007D01*
X31334Y573716D01*
X31584Y573299D01*
X31667Y572924D01*
X29917D01*
G01X27692Y575424D02*
X28025Y575341D01*
X28275Y575132D01*
X28442Y574882D01*
X28567Y574549D01*
X28609Y574174D01*
X28567Y573799D01*
X28442Y573466D01*
X28275Y573216D01*
X28025Y573007D01*
X27692Y572924D01*
X27359Y573007D01*
X27109Y573216D01*
X26942Y573466D01*
X26817Y573799D01*
X26775Y574174D01*
X26817Y574549D01*
X26942Y574882D01*
X27109Y575132D01*
X27359Y575341D01*
X27692Y575424D01*
G01X25300Y573216D02*
X25009Y573007D01*
X24675Y572924D01*
X24342Y573007D01*
X24050Y573257D01*
X23842Y573632D01*
X23759Y574007D01*
Y574466D01*
X23842Y574841D01*
X24050Y575174D01*
X24300Y575341D01*
X24592Y575424D01*
X24925Y575341D01*
X25175Y575174D01*
X25342Y574924D01*
X25425Y574591D01*
X25342Y574299D01*
X25134Y574007D01*
X24884Y573841D01*
X24592Y573799D01*
X24259Y573882D01*
X24009Y574091D01*
X23759Y574466D01*
G01X48756Y569795D02*
Y573795D01*
X56156D01*
G01X46323Y637276D02*
Y634776D01*
G01X47281Y637276D02*
X45365D01*
G01X44056Y634776D02*
Y637276D01*
X43056D01*
X42723Y637151D01*
X42473Y636859D01*
X42390Y636526D01*
X42473Y636193D01*
X42681Y635943D01*
X43056Y635818D01*
X44056D01*
G01X40123Y634776D02*
X39831Y634818D01*
X39498Y634943D01*
X39290Y635151D01*
X39206Y635443D01*
X39290Y635734D01*
X39540Y635984D01*
X39915Y636109D01*
X40331D01*
X40581Y636193D01*
X40790Y636401D01*
X40873Y636693D01*
X40748Y636984D01*
X40456Y637193D01*
X40123Y637276D01*
X39790Y637193D01*
X39498Y636984D01*
X39373Y636693D01*
X39456Y636401D01*
X39665Y636193D01*
X39915Y636109D01*
X40331D01*
X40706Y635984D01*
X40956Y635734D01*
X41040Y635443D01*
X40956Y635151D01*
X40748Y634943D01*
X40415Y634818D01*
X40123Y634776D01*
G01X37940Y635276D02*
X37690Y634984D01*
X37356Y634818D01*
X36981Y634776D01*
X36648Y634818D01*
X36315Y635026D01*
X36106Y635276D01*
X36065Y635526D01*
X36148Y635818D01*
X36440Y636026D01*
X36731Y636109D01*
X37106D01*
G01X36731D02*
X36481Y636234D01*
X36273Y636443D01*
X36190Y636693D01*
X36273Y636943D01*
X36481Y637151D01*
X36856Y637276D01*
X37231Y637234D01*
X37606Y637068D01*
G01X41023Y633209D02*
Y630709D01*
G01X41981Y633209D02*
X40065D01*
G01X38756Y630709D02*
Y633209D01*
X37756D01*
X37423Y633084D01*
X37173Y632792D01*
X37090Y632459D01*
X37173Y632126D01*
X37381Y631876D01*
X37756Y631751D01*
X38756D01*
G01X34906Y630709D02*
X34823Y631251D01*
X34698Y631709D01*
X34531Y632126D01*
X34323Y632584D01*
X33990Y633209D01*
X35656D01*
G01X32431Y631001D02*
X32140Y630792D01*
X31806Y630709D01*
X31473Y630792D01*
X31181Y631042D01*
X30973Y631417D01*
X30890Y631792D01*
Y632251D01*
X30973Y632626D01*
X31181Y632959D01*
X31431Y633126D01*
X31723Y633209D01*
X32056Y633126D01*
X32306Y632959D01*
X32473Y632709D01*
X32556Y632376D01*
X32473Y632084D01*
X32265Y631792D01*
X32015Y631626D01*
X31723Y631584D01*
X31390Y631667D01*
X31140Y631876D01*
X30890Y632251D01*
G01X41814Y621682D02*
Y619182D01*
G01X42772Y621682D02*
X40856D01*
G01X39547Y619182D02*
Y621682D01*
X38547D01*
X38214Y621557D01*
X37964Y621265D01*
X37881Y620932D01*
X37964Y620599D01*
X38172Y620349D01*
X38547Y620224D01*
X39547D01*
G01X35697Y619182D02*
X35614Y619724D01*
X35489Y620182D01*
X35322Y620599D01*
X35114Y621057D01*
X34781Y621682D01*
X36447D01*
G01X33306Y620224D02*
X33014Y620515D01*
X32764Y620682D01*
X32431Y620765D01*
X32139Y620682D01*
X31931Y620515D01*
X31764Y620265D01*
X31722Y619974D01*
X31764Y619724D01*
X31931Y619474D01*
X32181Y619265D01*
X32472Y619182D01*
X32806Y619265D01*
X33097Y619515D01*
X33264Y619890D01*
X33306Y620307D01*
X33222Y620849D01*
X33097Y621140D01*
X32889Y621432D01*
X32597Y621640D01*
X32306Y621682D01*
X32014Y621599D01*
X31806Y621390D01*
G01X28511Y625448D02*
Y622948D01*
G01X29469Y625448D02*
X27553D01*
G01X26244Y622948D02*
Y625448D01*
X25244D01*
X24911Y625323D01*
X24661Y625031D01*
X24578Y624698D01*
X24661Y624365D01*
X24869Y624115D01*
X25244Y623990D01*
X26244D01*
G01X22394Y622948D02*
X22311Y623490D01*
X22186Y623948D01*
X22019Y624365D01*
X21811Y624823D01*
X21478Y625448D01*
X23144D01*
G01X20128Y623448D02*
X19878Y623156D01*
X19544Y622990D01*
X19169Y622948D01*
X18836Y622990D01*
X18503Y623198D01*
X18294Y623448D01*
X18253Y623698D01*
X18336Y623990D01*
X18628Y624198D01*
X18919Y624281D01*
X19294D01*
G01X18919D02*
X18669Y624406D01*
X18461Y624615D01*
X18378Y624865D01*
X18461Y625115D01*
X18669Y625323D01*
X19044Y625448D01*
X19419Y625406D01*
X19794Y625240D01*
G01X28448Y617044D02*
Y614544D01*
G01X29406Y617044D02*
X27490D01*
G01X26181Y614544D02*
Y617044D01*
X25181D01*
X24848Y616919D01*
X24598Y616627D01*
X24515Y616294D01*
X24598Y615961D01*
X24806Y615711D01*
X25181Y615586D01*
X26181D01*
G01X22331Y614544D02*
X22248Y615086D01*
X22123Y615544D01*
X21956Y615961D01*
X21748Y616419D01*
X21415Y617044D01*
X23081D01*
G01X19148D02*
X19481Y616961D01*
X19731Y616752D01*
X19898Y616502D01*
X20023Y616169D01*
X20065Y615794D01*
X20023Y615419D01*
X19898Y615086D01*
X19731Y614836D01*
X19481Y614627D01*
X19148Y614544D01*
X18815Y614627D01*
X18565Y614836D01*
X18398Y615086D01*
X18273Y615419D01*
X18231Y615794D01*
X18273Y616169D01*
X18398Y616502D01*
X18565Y616752D01*
X18815Y616961D01*
X19148Y617044D01*
G01X28511Y629448D02*
Y626948D01*
G01X29469Y629448D02*
X27553D01*
G01X26244Y626948D02*
Y629448D01*
X25244D01*
X24911Y629323D01*
X24661Y629031D01*
X24578Y628698D01*
X24661Y628365D01*
X24869Y628115D01*
X25244Y627990D01*
X26244D01*
G01X23228Y627323D02*
X22978Y627115D01*
X22686Y626990D01*
X22311Y626948D01*
X21936Y627031D01*
X21644Y627198D01*
X21436Y627490D01*
X21394Y627823D01*
X21478Y628156D01*
X21686Y628365D01*
X21978Y628531D01*
X22269Y628573D01*
X22561Y628531D01*
X22936Y628365D01*
X22811Y629448D01*
X21686D01*
G01X18711Y626948D02*
Y629448D01*
X20253Y627656D01*
X18169D01*
G01X33123Y637776D02*
Y635276D01*
G01X34081Y637776D02*
X32165D01*
G01X30856Y635276D02*
Y637776D01*
X29856D01*
X29523Y637651D01*
X29273Y637359D01*
X29190Y637026D01*
X29273Y636693D01*
X29481Y636443D01*
X29856Y636318D01*
X30856D01*
G01X27840Y635651D02*
X27590Y635443D01*
X27298Y635318D01*
X26923Y635276D01*
X26548Y635359D01*
X26256Y635526D01*
X26048Y635818D01*
X26006Y636151D01*
X26090Y636484D01*
X26298Y636693D01*
X26590Y636859D01*
X26881Y636901D01*
X27173Y636859D01*
X27548Y636693D01*
X27423Y637776D01*
X26298D01*
G01X24615Y637359D02*
X24365Y637609D01*
X24073Y637734D01*
X23740Y637776D01*
X23323Y637693D01*
X23031Y637484D01*
X22948Y637234D01*
X22990Y636984D01*
X23156Y636776D01*
X23990Y636359D01*
X24365Y636068D01*
X24615Y635651D01*
X24698Y635276D01*
X22948D01*
G01X39270Y583754D02*
X39520Y583879D01*
X39812Y583962D01*
X40145D01*
X40520Y583837D01*
X40812Y583629D01*
X41020Y583379D01*
X41187Y582962D01*
X41229Y582587D01*
X41145Y582212D01*
X41020Y581962D01*
X40770Y581712D01*
X40479Y581545D01*
X40187Y581462D01*
X39895D01*
X39604Y581545D01*
X39354Y581670D01*
X39145Y581837D01*
G01X37879Y582504D02*
X37587Y582795D01*
X37337Y582962D01*
X37004Y583045D01*
X36712Y582962D01*
X36504Y582795D01*
X36337Y582545D01*
X36295Y582254D01*
X36337Y582004D01*
X36504Y581754D01*
X36754Y581545D01*
X37045Y581462D01*
X37379Y581545D01*
X37670Y581795D01*
X37837Y582170D01*
X37879Y582587D01*
X37795Y583129D01*
X37670Y583420D01*
X37462Y583712D01*
X37170Y583920D01*
X36879Y583962D01*
X36587Y583879D01*
X36379Y583670D01*
G01X34779Y583545D02*
X34529Y583795D01*
X34237Y583920D01*
X33904Y583962D01*
X33487Y583879D01*
X33195Y583670D01*
X33112Y583420D01*
X33154Y583170D01*
X33320Y582962D01*
X34154Y582545D01*
X34529Y582254D01*
X34779Y581837D01*
X34862Y581462D01*
X33112D01*
G01X65292Y590317D02*
X65417Y590067D01*
X65500Y589775D01*
Y589442D01*
X65375Y589067D01*
X65167Y588775D01*
X64917Y588567D01*
X64500Y588400D01*
X64125Y588358D01*
X63750Y588442D01*
X63500Y588567D01*
X63250Y588817D01*
X63083Y589108D01*
X63000Y589400D01*
Y589692D01*
X63083Y589983D01*
X63208Y590233D01*
X63375Y590442D01*
G01X64042Y591708D02*
X64333Y592000D01*
X64500Y592250D01*
X64583Y592583D01*
X64500Y592875D01*
X64333Y593083D01*
X64083Y593250D01*
X63792Y593292D01*
X63542Y593250D01*
X63292Y593083D01*
X63083Y592833D01*
X63000Y592542D01*
X63083Y592208D01*
X63333Y591917D01*
X63708Y591750D01*
X64125Y591708D01*
X64667Y591792D01*
X64958Y591917D01*
X65250Y592125D01*
X65458Y592417D01*
X65500Y592708D01*
X65417Y593000D01*
X65208Y593208D01*
G01X63000Y595600D02*
X65500D01*
X65000Y595100D01*
G01X63000D02*
Y596100D01*
G01X70733Y682792D02*
X70983Y682917D01*
X71275Y683000D01*
X71608D01*
X71983Y682875D01*
X72275Y682667D01*
X72483Y682417D01*
X72650Y682000D01*
X72692Y681625D01*
X72608Y681250D01*
X72483Y681000D01*
X72233Y680750D01*
X71942Y680583D01*
X71650Y680500D01*
X71358D01*
X71067Y680583D01*
X70817Y680708D01*
X70608Y680875D01*
G01X69258Y680792D02*
X68967Y680583D01*
X68633Y680500D01*
X68300Y680583D01*
X68008Y680833D01*
X67800Y681208D01*
X67717Y681583D01*
Y682042D01*
X67800Y682417D01*
X68008Y682750D01*
X68258Y682917D01*
X68550Y683000D01*
X68883Y682917D01*
X69133Y682750D01*
X69300Y682500D01*
X69383Y682167D01*
X69300Y681875D01*
X69092Y681583D01*
X68842Y681417D01*
X68550Y681375D01*
X68217Y681458D01*
X67967Y681667D01*
X67717Y682042D01*
G01X66158Y680792D02*
X65867Y680583D01*
X65533Y680500D01*
X65200Y680583D01*
X64908Y680833D01*
X64700Y681208D01*
X64617Y681583D01*
Y682042D01*
X64700Y682417D01*
X64908Y682750D01*
X65158Y682917D01*
X65450Y683000D01*
X65783Y682917D01*
X66033Y682750D01*
X66200Y682500D01*
X66283Y682167D01*
X66200Y681875D01*
X65992Y681583D01*
X65742Y681417D01*
X65450Y681375D01*
X65117Y681458D01*
X64867Y681667D01*
X64617Y682042D01*
G01X63058Y680792D02*
X62767Y680583D01*
X62433Y680500D01*
X62100Y680583D01*
X61808Y680833D01*
X61600Y681208D01*
X61517Y681583D01*
Y682042D01*
X61600Y682417D01*
X61808Y682750D01*
X62058Y682917D01*
X62350Y683000D01*
X62683Y682917D01*
X62933Y682750D01*
X63100Y682500D01*
X63183Y682167D01*
X63100Y681875D01*
X62892Y681583D01*
X62642Y681417D01*
X62350Y681375D01*
X62017Y681458D01*
X61767Y681667D01*
X61517Y682042D01*
G01X61004Y644936D02*
Y647436D01*
X59963D01*
X59629Y647311D01*
X59421Y647144D01*
X59338Y646811D01*
X59421Y646478D01*
X59671Y646269D01*
X59963Y646144D01*
X61004D01*
G01X59963D02*
X59338Y644936D01*
G01X57988Y645436D02*
X57738Y645144D01*
X57404Y644978D01*
X57029Y644936D01*
X56696Y644978D01*
X56363Y645186D01*
X56154Y645436D01*
X56113Y645686D01*
X56196Y645978D01*
X56488Y646186D01*
X56779Y646269D01*
X57154D01*
G01X56779D02*
X56529Y646394D01*
X56321Y646603D01*
X56238Y646853D01*
X56321Y647103D01*
X56529Y647311D01*
X56904Y647436D01*
X57279Y647394D01*
X57654Y647228D01*
G01X54763Y645978D02*
X54471Y646269D01*
X54221Y646436D01*
X53888Y646519D01*
X53596Y646436D01*
X53388Y646269D01*
X53221Y646019D01*
X53179Y645728D01*
X53221Y645478D01*
X53388Y645228D01*
X53638Y645019D01*
X53929Y644936D01*
X54263Y645019D01*
X54554Y645269D01*
X54721Y645644D01*
X54763Y646061D01*
X54679Y646603D01*
X54554Y646894D01*
X54346Y647186D01*
X54054Y647394D01*
X53763Y647436D01*
X53471Y647353D01*
X53263Y647144D01*
G01X51788Y645311D02*
X51538Y645103D01*
X51246Y644978D01*
X50871Y644936D01*
X50496Y645019D01*
X50204Y645186D01*
X49996Y645478D01*
X49954Y645811D01*
X50038Y646144D01*
X50246Y646353D01*
X50538Y646519D01*
X50829Y646561D01*
X51121Y646519D01*
X51496Y646353D01*
X51371Y647436D01*
X50246D01*
G01X65934Y642326D02*
X68434D01*
Y643367D01*
X68309Y643701D01*
X68142Y643909D01*
X67809Y643992D01*
X67476Y643909D01*
X67267Y643659D01*
X67142Y643367D01*
Y642326D01*
G01Y643367D02*
X65934Y643992D01*
G01X66434Y645342D02*
X66142Y645592D01*
X65976Y645926D01*
X65934Y646301D01*
X65976Y646634D01*
X66184Y646967D01*
X66434Y647176D01*
X66684Y647217D01*
X66976Y647134D01*
X67184Y646842D01*
X67267Y646551D01*
Y646176D01*
G01Y646551D02*
X67392Y646801D01*
X67601Y647009D01*
X67851Y647092D01*
X68101Y647009D01*
X68309Y646801D01*
X68434Y646426D01*
X68392Y646051D01*
X68226Y645676D01*
G01X65934Y649359D02*
X65976Y649651D01*
X66101Y649984D01*
X66309Y650192D01*
X66601Y650276D01*
X66892Y650192D01*
X67142Y649942D01*
X67267Y649567D01*
Y649151D01*
X67351Y648901D01*
X67559Y648692D01*
X67851Y648609D01*
X68142Y648734D01*
X68351Y649026D01*
X68434Y649359D01*
X68351Y649692D01*
X68142Y649984D01*
X67851Y650109D01*
X67559Y650026D01*
X67351Y649817D01*
X67267Y649567D01*
Y649151D01*
X67142Y648776D01*
X66892Y648526D01*
X66601Y648442D01*
X66309Y648526D01*
X66101Y648734D01*
X65976Y649067D01*
X65934Y649359D01*
G01Y652959D02*
X68434D01*
X66642Y651417D01*
Y653501D01*
G01X60731Y640086D02*
Y642586D01*
X59690D01*
X59356Y642461D01*
X59148Y642294D01*
X59065Y641961D01*
X59148Y641628D01*
X59398Y641419D01*
X59690Y641294D01*
X60731D01*
G01X59690D02*
X59065Y640086D01*
G01X57715Y640586D02*
X57465Y640294D01*
X57131Y640128D01*
X56756Y640086D01*
X56423Y640128D01*
X56090Y640336D01*
X55881Y640586D01*
X55840Y640836D01*
X55923Y641128D01*
X56215Y641336D01*
X56506Y641419D01*
X56881D01*
G01X56506D02*
X56256Y641544D01*
X56048Y641753D01*
X55965Y642003D01*
X56048Y642253D01*
X56256Y642461D01*
X56631Y642586D01*
X57006Y642544D01*
X57381Y642378D01*
G01X54490Y641128D02*
X54198Y641419D01*
X53948Y641586D01*
X53615Y641669D01*
X53323Y641586D01*
X53115Y641419D01*
X52948Y641169D01*
X52906Y640878D01*
X52948Y640628D01*
X53115Y640378D01*
X53365Y640169D01*
X53656Y640086D01*
X53990Y640169D01*
X54281Y640419D01*
X54448Y640794D01*
X54490Y641211D01*
X54406Y641753D01*
X54281Y642044D01*
X54073Y642336D01*
X53781Y642544D01*
X53490Y642586D01*
X53198Y642503D01*
X52990Y642294D01*
G01X50598Y642586D02*
X50931Y642503D01*
X51181Y642294D01*
X51348Y642044D01*
X51473Y641711D01*
X51515Y641336D01*
X51473Y640961D01*
X51348Y640628D01*
X51181Y640378D01*
X50931Y640169D01*
X50598Y640086D01*
X50265Y640169D01*
X50015Y640378D01*
X49848Y640628D01*
X49723Y640961D01*
X49681Y641336D01*
X49723Y641711D01*
X49848Y642044D01*
X50015Y642294D01*
X50265Y642503D01*
X50598Y642586D01*
G01X61156Y649170D02*
Y651670D01*
X60115D01*
X59781Y651545D01*
X59573Y651378D01*
X59490Y651045D01*
X59573Y650712D01*
X59823Y650503D01*
X60115Y650378D01*
X61156D01*
G01X60115D02*
X59490Y649170D01*
G01X58140Y649670D02*
X57890Y649378D01*
X57556Y649212D01*
X57181Y649170D01*
X56848Y649212D01*
X56515Y649420D01*
X56306Y649670D01*
X56265Y649920D01*
X56348Y650212D01*
X56640Y650420D01*
X56931Y650503D01*
X57306D01*
G01X56931D02*
X56681Y650628D01*
X56473Y650837D01*
X56390Y651087D01*
X56473Y651337D01*
X56681Y651545D01*
X57056Y651670D01*
X57431Y651628D01*
X57806Y651462D01*
G01X55040Y649545D02*
X54790Y649337D01*
X54498Y649212D01*
X54123Y649170D01*
X53748Y649253D01*
X53456Y649420D01*
X53248Y649712D01*
X53206Y650045D01*
X53290Y650378D01*
X53498Y650587D01*
X53790Y650753D01*
X54081Y650795D01*
X54373Y650753D01*
X54748Y650587D01*
X54623Y651670D01*
X53498D01*
G01X51731Y649462D02*
X51440Y649253D01*
X51106Y649170D01*
X50773Y649253D01*
X50481Y649503D01*
X50273Y649878D01*
X50190Y650253D01*
Y650712D01*
X50273Y651087D01*
X50481Y651420D01*
X50731Y651587D01*
X51023Y651670D01*
X51356Y651587D01*
X51606Y651420D01*
X51773Y651170D01*
X51856Y650837D01*
X51773Y650545D01*
X51565Y650253D01*
X51315Y650087D01*
X51023Y650045D01*
X50690Y650128D01*
X50440Y650337D01*
X50190Y650712D01*
G01X46323Y647576D02*
Y645076D01*
G01X47281Y647576D02*
X45365D01*
G01X44056Y645076D02*
Y647576D01*
X43056D01*
X42723Y647451D01*
X42473Y647159D01*
X42390Y646826D01*
X42473Y646493D01*
X42681Y646243D01*
X43056Y646118D01*
X44056D01*
G01X40123Y645076D02*
X39831Y645118D01*
X39498Y645243D01*
X39290Y645451D01*
X39206Y645743D01*
X39290Y646034D01*
X39540Y646284D01*
X39915Y646409D01*
X40331D01*
X40581Y646493D01*
X40790Y646701D01*
X40873Y646993D01*
X40748Y647284D01*
X40456Y647493D01*
X40123Y647576D01*
X39790Y647493D01*
X39498Y647284D01*
X39373Y646993D01*
X39456Y646701D01*
X39665Y646493D01*
X39915Y646409D01*
X40331D01*
X40706Y646284D01*
X40956Y646034D01*
X41040Y645743D01*
X40956Y645451D01*
X40748Y645243D01*
X40415Y645118D01*
X40123Y645076D01*
G01X37815Y647159D02*
X37565Y647409D01*
X37273Y647534D01*
X36940Y647576D01*
X36523Y647493D01*
X36231Y647284D01*
X36148Y647034D01*
X36190Y646784D01*
X36356Y646576D01*
X37190Y646159D01*
X37565Y645868D01*
X37815Y645451D01*
X37898Y645076D01*
X36148D01*
G01X45823Y642776D02*
Y640276D01*
G01X46781Y642776D02*
X44865D01*
G01X43556Y640276D02*
Y642776D01*
X42556D01*
X42223Y642651D01*
X41973Y642359D01*
X41890Y642026D01*
X41973Y641693D01*
X42181Y641443D01*
X42556Y641318D01*
X43556D01*
G01X39623Y640276D02*
X39331Y640318D01*
X38998Y640443D01*
X38790Y640651D01*
X38706Y640943D01*
X38790Y641234D01*
X39040Y641484D01*
X39415Y641609D01*
X39831D01*
X40081Y641693D01*
X40290Y641901D01*
X40373Y642193D01*
X40248Y642484D01*
X39956Y642693D01*
X39623Y642776D01*
X39290Y642693D01*
X38998Y642484D01*
X38873Y642193D01*
X38956Y641901D01*
X39165Y641693D01*
X39415Y641609D01*
X39831D01*
X40206Y641484D01*
X40456Y641234D01*
X40540Y640943D01*
X40456Y640651D01*
X40248Y640443D01*
X39915Y640318D01*
X39623Y640276D01*
G01X36523D02*
Y642776D01*
X37023Y642276D01*
G01Y640276D02*
X36023D01*
G01X46423Y652376D02*
Y649876D01*
G01X47381Y652376D02*
X45465D01*
G01X44156Y649876D02*
Y652376D01*
X43156D01*
X42823Y652251D01*
X42573Y651959D01*
X42490Y651626D01*
X42573Y651293D01*
X42781Y651043D01*
X43156Y650918D01*
X44156D01*
G01X40223Y649876D02*
X39931Y649918D01*
X39598Y650043D01*
X39390Y650251D01*
X39306Y650543D01*
X39390Y650834D01*
X39640Y651084D01*
X40015Y651209D01*
X40431D01*
X40681Y651293D01*
X40890Y651501D01*
X40973Y651793D01*
X40848Y652084D01*
X40556Y652293D01*
X40223Y652376D01*
X39890Y652293D01*
X39598Y652084D01*
X39473Y651793D01*
X39556Y651501D01*
X39765Y651293D01*
X40015Y651209D01*
X40431D01*
X40806Y651084D01*
X41056Y650834D01*
X41140Y650543D01*
X41056Y650251D01*
X40848Y650043D01*
X40515Y649918D01*
X40223Y649876D01*
G01X37123Y652376D02*
X37456Y652293D01*
X37706Y652084D01*
X37873Y651834D01*
X37998Y651501D01*
X38040Y651126D01*
X37998Y650751D01*
X37873Y650418D01*
X37706Y650168D01*
X37456Y649959D01*
X37123Y649876D01*
X36790Y649959D01*
X36540Y650168D01*
X36373Y650418D01*
X36248Y650751D01*
X36206Y651126D01*
X36248Y651501D01*
X36373Y651834D01*
X36540Y652084D01*
X36790Y652293D01*
X37123Y652376D01*
G01X70833Y678792D02*
X71083Y678917D01*
X71375Y679000D01*
X71708D01*
X72083Y678875D01*
X72375Y678667D01*
X72583Y678417D01*
X72750Y678000D01*
X72792Y677625D01*
X72708Y677250D01*
X72583Y677000D01*
X72333Y676750D01*
X72042Y676583D01*
X71750Y676500D01*
X71458D01*
X71167Y676583D01*
X70917Y676708D01*
X70708Y676875D01*
G01X69358Y676792D02*
X69067Y676583D01*
X68733Y676500D01*
X68400Y676583D01*
X68108Y676833D01*
X67900Y677208D01*
X67817Y677583D01*
Y678042D01*
X67900Y678417D01*
X68108Y678750D01*
X68358Y678917D01*
X68650Y679000D01*
X68983Y678917D01*
X69233Y678750D01*
X69400Y678500D01*
X69483Y678167D01*
X69400Y677875D01*
X69192Y677583D01*
X68942Y677417D01*
X68650Y677375D01*
X68317Y677458D01*
X68067Y677667D01*
X67817Y678042D01*
G01X66258Y676792D02*
X65967Y676583D01*
X65633Y676500D01*
X65300Y676583D01*
X65008Y676833D01*
X64800Y677208D01*
X64717Y677583D01*
Y678042D01*
X64800Y678417D01*
X65008Y678750D01*
X65258Y678917D01*
X65550Y679000D01*
X65883Y678917D01*
X66133Y678750D01*
X66300Y678500D01*
X66383Y678167D01*
X66300Y677875D01*
X66092Y677583D01*
X65842Y677417D01*
X65550Y677375D01*
X65217Y677458D01*
X64967Y677667D01*
X64717Y678042D01*
G01X62450Y676500D02*
X62158Y676542D01*
X61825Y676667D01*
X61617Y676875D01*
X61533Y677167D01*
X61617Y677458D01*
X61867Y677708D01*
X62242Y677833D01*
X62658D01*
X62908Y677917D01*
X63117Y678125D01*
X63200Y678417D01*
X63075Y678708D01*
X62783Y678917D01*
X62450Y679000D01*
X62117Y678917D01*
X61825Y678708D01*
X61700Y678417D01*
X61783Y678125D01*
X61992Y677917D01*
X62242Y677833D01*
X62658D01*
X63033Y677708D01*
X63283Y677458D01*
X63367Y677167D01*
X63283Y676875D01*
X63075Y676667D01*
X62742Y676542D01*
X62450Y676500D01*
G01X139316Y453835D02*
X141816D01*
Y454876D01*
X141691Y455210D01*
X141524Y455418D01*
X141191Y455501D01*
X140858Y455418D01*
X140649Y455168D01*
X140524Y454876D01*
Y453835D01*
G01Y454876D02*
X139316Y455501D01*
G01X141399Y456976D02*
X141649Y457226D01*
X141774Y457518D01*
X141816Y457851D01*
X141733Y458268D01*
X141524Y458560D01*
X141274Y458643D01*
X141024Y458601D01*
X140816Y458435D01*
X140399Y457601D01*
X140108Y457226D01*
X139691Y456976D01*
X139316Y456893D01*
Y458643D01*
G01Y460785D02*
X139858Y460868D01*
X140316Y460993D01*
X140733Y461160D01*
X141191Y461368D01*
X141816Y461701D01*
Y460035D01*
G01Y463968D02*
X141733Y463635D01*
X141524Y463385D01*
X141274Y463218D01*
X140941Y463093D01*
X140566Y463051D01*
X140191Y463093D01*
X139858Y463218D01*
X139608Y463385D01*
X139399Y463635D01*
X139316Y463968D01*
X139399Y464301D01*
X139608Y464551D01*
X139858Y464718D01*
X140191Y464843D01*
X140566Y464885D01*
X140941Y464843D01*
X141274Y464718D01*
X141524Y464551D01*
X141733Y464301D01*
X141816Y463968D01*
G01X137765Y440690D02*
X140265D01*
Y441731D01*
X140140Y442065D01*
X139973Y442273D01*
X139640Y442356D01*
X139307Y442273D01*
X139098Y442023D01*
X138973Y441731D01*
Y440690D01*
G01Y441731D02*
X137765Y442356D01*
G01X138265Y443706D02*
X137973Y443956D01*
X137807Y444290D01*
X137765Y444665D01*
X137807Y444998D01*
X138015Y445331D01*
X138265Y445540D01*
X138515Y445581D01*
X138807Y445498D01*
X139015Y445206D01*
X139098Y444915D01*
Y444540D01*
G01Y444915D02*
X139223Y445165D01*
X139432Y445373D01*
X139682Y445456D01*
X139932Y445373D01*
X140140Y445165D01*
X140265Y444790D01*
X140223Y444415D01*
X140057Y444040D01*
G01X138807Y446931D02*
X139098Y447223D01*
X139265Y447473D01*
X139348Y447806D01*
X139265Y448098D01*
X139098Y448306D01*
X138848Y448473D01*
X138557Y448515D01*
X138307Y448473D01*
X138057Y448306D01*
X137848Y448056D01*
X137765Y447765D01*
X137848Y447431D01*
X138098Y447140D01*
X138473Y446973D01*
X138890Y446931D01*
X139432Y447015D01*
X139723Y447140D01*
X140015Y447348D01*
X140223Y447640D01*
X140265Y447931D01*
X140182Y448223D01*
X139973Y448431D01*
G01X139848Y450031D02*
X140098Y450281D01*
X140223Y450573D01*
X140265Y450906D01*
X140182Y451323D01*
X139973Y451615D01*
X139723Y451698D01*
X139473Y451656D01*
X139265Y451490D01*
X138848Y450656D01*
X138557Y450281D01*
X138140Y450031D01*
X137765Y449948D01*
Y451698D01*
G01X131000Y469167D02*
X133500D01*
Y470208D01*
X133375Y470542D01*
X133208Y470750D01*
X132875Y470833D01*
X132542Y470750D01*
X132333Y470500D01*
X132208Y470208D01*
Y469167D01*
G01Y470208D02*
X131000Y470833D01*
G01X131292Y472392D02*
X131083Y472683D01*
X131000Y473017D01*
X131083Y473350D01*
X131333Y473642D01*
X131708Y473850D01*
X132083Y473933D01*
X132542D01*
X132917Y473850D01*
X133250Y473642D01*
X133417Y473392D01*
X133500Y473100D01*
X133417Y472767D01*
X133250Y472517D01*
X133000Y472350D01*
X132667Y472267D01*
X132375Y472350D01*
X132083Y472558D01*
X131917Y472808D01*
X131875Y473100D01*
X131958Y473433D01*
X132167Y473683D01*
X132542Y473933D01*
G01X131000Y476200D02*
X133500D01*
X133000Y475700D01*
G01X131000D02*
Y476700D01*
G01X126800Y468967D02*
X129300D01*
Y470008D01*
X129175Y470342D01*
X129008Y470550D01*
X128675Y470633D01*
X128342Y470550D01*
X128133Y470300D01*
X128008Y470008D01*
Y468967D01*
G01Y470008D02*
X126800Y470633D01*
G01X127092Y472192D02*
X126883Y472483D01*
X126800Y472817D01*
X126883Y473150D01*
X127133Y473442D01*
X127508Y473650D01*
X127883Y473733D01*
X128342D01*
X128717Y473650D01*
X129050Y473442D01*
X129217Y473192D01*
X129300Y472900D01*
X129217Y472567D01*
X129050Y472317D01*
X128800Y472150D01*
X128467Y472067D01*
X128175Y472150D01*
X127883Y472358D01*
X127717Y472608D01*
X127675Y472900D01*
X127758Y473233D01*
X127967Y473483D01*
X128342Y473733D01*
G01X129300Y476000D02*
X129217Y475667D01*
X129008Y475417D01*
X128758Y475250D01*
X128425Y475125D01*
X128050Y475083D01*
X127675Y475125D01*
X127342Y475250D01*
X127092Y475417D01*
X126883Y475667D01*
X126800Y476000D01*
X126883Y476333D01*
X127092Y476583D01*
X127342Y476750D01*
X127675Y476875D01*
X128050Y476917D01*
X128425Y476875D01*
X128758Y476750D01*
X129008Y476583D01*
X129217Y476333D01*
X129300Y476000D01*
G01X135007Y453747D02*
X137507D01*
Y454788D01*
X137382Y455122D01*
X137215Y455330D01*
X136882Y455413D01*
X136549Y455330D01*
X136340Y455080D01*
X136215Y454788D01*
Y453747D01*
G01Y454788D02*
X135007Y455413D01*
G01X135507Y456763D02*
X135215Y457013D01*
X135049Y457347D01*
X135007Y457722D01*
X135049Y458055D01*
X135257Y458388D01*
X135507Y458597D01*
X135757Y458638D01*
X136049Y458555D01*
X136257Y458263D01*
X136340Y457972D01*
Y457597D01*
G01Y457972D02*
X136465Y458222D01*
X136674Y458430D01*
X136924Y458513D01*
X137174Y458430D01*
X137382Y458222D01*
X137507Y457847D01*
X137465Y457472D01*
X137299Y457097D01*
G01X137090Y459988D02*
X137340Y460238D01*
X137465Y460530D01*
X137507Y460863D01*
X137424Y461280D01*
X137215Y461572D01*
X136965Y461655D01*
X136715Y461613D01*
X136507Y461447D01*
X136090Y460613D01*
X135799Y460238D01*
X135382Y459988D01*
X135007Y459905D01*
Y461655D01*
G01X135382Y462963D02*
X135174Y463213D01*
X135049Y463505D01*
X135007Y463880D01*
X135090Y464255D01*
X135257Y464547D01*
X135549Y464755D01*
X135882Y464797D01*
X136215Y464713D01*
X136424Y464505D01*
X136590Y464213D01*
X136632Y463922D01*
X136590Y463630D01*
X136424Y463255D01*
X137507Y463380D01*
Y464505D01*
G01X133000Y439717D02*
X135500D01*
Y440758D01*
X135375Y441092D01*
X135208Y441300D01*
X134875Y441383D01*
X134542Y441300D01*
X134333Y441050D01*
X134208Y440758D01*
Y439717D01*
G01Y440758D02*
X133000Y441383D01*
G01X133500Y442733D02*
X133208Y442983D01*
X133042Y443317D01*
X133000Y443692D01*
X133042Y444025D01*
X133250Y444358D01*
X133500Y444567D01*
X133750Y444608D01*
X134042Y444525D01*
X134250Y444233D01*
X134333Y443942D01*
Y443567D01*
G01Y443942D02*
X134458Y444192D01*
X134667Y444400D01*
X134917Y444483D01*
X135167Y444400D01*
X135375Y444192D01*
X135500Y443817D01*
X135458Y443442D01*
X135292Y443067D01*
G01X133375Y445833D02*
X133167Y446083D01*
X133042Y446375D01*
X133000Y446750D01*
X133083Y447125D01*
X133250Y447417D01*
X133542Y447625D01*
X133875Y447667D01*
X134208Y447583D01*
X134417Y447375D01*
X134583Y447083D01*
X134625Y446792D01*
X134583Y446500D01*
X134417Y446125D01*
X135500Y446250D01*
Y447375D01*
G01Y449850D02*
X135417Y449517D01*
X135208Y449267D01*
X134958Y449100D01*
X134625Y448975D01*
X134250Y448933D01*
X133875Y448975D01*
X133542Y449100D01*
X133292Y449267D01*
X133083Y449517D01*
X133000Y449850D01*
X133083Y450183D01*
X133292Y450433D01*
X133542Y450600D01*
X133875Y450725D01*
X134250Y450767D01*
X134625Y450725D01*
X134958Y450600D01*
X135208Y450433D01*
X135417Y450183D01*
X135500Y449850D01*
G01X131007Y453747D02*
X133507D01*
Y454788D01*
X133382Y455122D01*
X133215Y455330D01*
X132882Y455413D01*
X132549Y455330D01*
X132340Y455080D01*
X132215Y454788D01*
Y453747D01*
G01Y454788D02*
X131007Y455413D01*
G01X131507Y456763D02*
X131215Y457013D01*
X131049Y457347D01*
X131007Y457722D01*
X131049Y458055D01*
X131257Y458388D01*
X131507Y458597D01*
X131757Y458638D01*
X132049Y458555D01*
X132257Y458263D01*
X132340Y457972D01*
Y457597D01*
G01Y457972D02*
X132465Y458222D01*
X132674Y458430D01*
X132924Y458513D01*
X133174Y458430D01*
X133382Y458222D01*
X133507Y457847D01*
X133465Y457472D01*
X133299Y457097D01*
G01X131007Y460780D02*
X133507D01*
X133007Y460280D01*
G01X131007D02*
Y461280D01*
G01Y464380D02*
X133507D01*
X131715Y462838D01*
Y464922D01*
G01X149849Y466100D02*
Y468600D01*
X148808D01*
X148474Y468475D01*
X148266Y468308D01*
X148183Y467975D01*
X148266Y467642D01*
X148516Y467433D01*
X148808Y467308D01*
X149849D01*
G01X148808D02*
X148183Y466100D01*
G01X146708Y468183D02*
X146458Y468433D01*
X146166Y468558D01*
X145833Y468600D01*
X145416Y468517D01*
X145124Y468308D01*
X145041Y468058D01*
X145083Y467808D01*
X145249Y467600D01*
X146083Y467183D01*
X146458Y466892D01*
X146708Y466475D01*
X146791Y466100D01*
X145041D01*
G01X143524Y466392D02*
X143233Y466183D01*
X142899Y466100D01*
X142566Y466183D01*
X142274Y466433D01*
X142066Y466808D01*
X141983Y467183D01*
Y467642D01*
X142066Y468017D01*
X142274Y468350D01*
X142524Y468517D01*
X142816Y468600D01*
X143149Y468517D01*
X143399Y468350D01*
X143566Y468100D01*
X143649Y467767D01*
X143566Y467475D01*
X143358Y467183D01*
X143108Y467017D01*
X142816Y466975D01*
X142483Y467058D01*
X142233Y467267D01*
X141983Y467642D01*
G01X140633Y466600D02*
X140383Y466308D01*
X140049Y466142D01*
X139674Y466100D01*
X139341Y466142D01*
X139008Y466350D01*
X138799Y466600D01*
X138758Y466850D01*
X138841Y467142D01*
X139133Y467350D01*
X139424Y467433D01*
X139799D01*
G01X139424D02*
X139174Y467558D01*
X138966Y467767D01*
X138883Y468017D01*
X138966Y468267D01*
X139174Y468475D01*
X139549Y468600D01*
X139924Y468558D01*
X140299Y468392D01*
G01X116507Y453747D02*
X119007D01*
Y454788D01*
X118882Y455122D01*
X118715Y455330D01*
X118382Y455413D01*
X118049Y455330D01*
X117840Y455080D01*
X117715Y454788D01*
Y453747D01*
G01Y454788D02*
X116507Y455413D01*
G01Y457597D02*
X117049Y457680D01*
X117507Y457805D01*
X117924Y457972D01*
X118382Y458180D01*
X119007Y458513D01*
Y456847D01*
G01X117007Y459863D02*
X116715Y460113D01*
X116549Y460447D01*
X116507Y460822D01*
X116549Y461155D01*
X116757Y461488D01*
X117007Y461697D01*
X117257Y461738D01*
X117549Y461655D01*
X117757Y461363D01*
X117840Y461072D01*
Y460697D01*
G01Y461072D02*
X117965Y461322D01*
X118174Y461530D01*
X118424Y461613D01*
X118674Y461530D01*
X118882Y461322D01*
X119007Y460947D01*
X118965Y460572D01*
X118799Y460197D01*
G01X116507Y464380D02*
X119007D01*
X117215Y462838D01*
Y464922D01*
G01X120111Y453757D02*
X122611D01*
Y454798D01*
X122486Y455132D01*
X122319Y455340D01*
X121986Y455423D01*
X121653Y455340D01*
X121444Y455090D01*
X121319Y454798D01*
Y453757D01*
G01Y454798D02*
X120111Y455423D01*
G01Y457607D02*
X120653Y457690D01*
X121111Y457815D01*
X121528Y457982D01*
X121986Y458190D01*
X122611Y458523D01*
Y456857D01*
G01X120611Y459873D02*
X120319Y460123D01*
X120153Y460457D01*
X120111Y460832D01*
X120153Y461165D01*
X120361Y461498D01*
X120611Y461707D01*
X120861Y461748D01*
X121153Y461665D01*
X121361Y461373D01*
X121444Y461082D01*
Y460707D01*
G01Y461082D02*
X121569Y461332D01*
X121778Y461540D01*
X122028Y461623D01*
X122278Y461540D01*
X122486Y461332D01*
X122611Y460957D01*
X122569Y460582D01*
X122403Y460207D01*
G01X122194Y463098D02*
X122444Y463348D01*
X122569Y463640D01*
X122611Y463973D01*
X122528Y464390D01*
X122319Y464682D01*
X122069Y464765D01*
X121819Y464723D01*
X121611Y464557D01*
X121194Y463723D01*
X120903Y463348D01*
X120486Y463098D01*
X120111Y463015D01*
Y464765D01*
G01X124801Y453747D02*
X127301D01*
Y454788D01*
X127176Y455122D01*
X127009Y455330D01*
X126676Y455413D01*
X126343Y455330D01*
X126134Y455080D01*
X126009Y454788D01*
Y453747D01*
G01Y454788D02*
X124801Y455413D01*
G01X125301Y456763D02*
X125009Y457013D01*
X124843Y457347D01*
X124801Y457722D01*
X124843Y458055D01*
X125051Y458388D01*
X125301Y458597D01*
X125551Y458638D01*
X125843Y458555D01*
X126051Y458263D01*
X126134Y457972D01*
Y457597D01*
G01Y457972D02*
X126259Y458222D01*
X126468Y458430D01*
X126718Y458513D01*
X126968Y458430D01*
X127176Y458222D01*
X127301Y457847D01*
X127259Y457472D01*
X127093Y457097D01*
G01X124801Y461280D02*
X127301D01*
X125509Y459738D01*
Y461822D01*
G01X124801Y463880D02*
X124843Y464172D01*
X124968Y464505D01*
X125176Y464713D01*
X125468Y464797D01*
X125759Y464713D01*
X126009Y464463D01*
X126134Y464088D01*
Y463672D01*
X126218Y463422D01*
X126426Y463213D01*
X126718Y463130D01*
X127009Y463255D01*
X127218Y463547D01*
X127301Y463880D01*
X127218Y464213D01*
X127009Y464505D01*
X126718Y464630D01*
X126426Y464547D01*
X126218Y464338D01*
X126134Y464088D01*
Y463672D01*
X126009Y463297D01*
X125759Y463047D01*
X125468Y462963D01*
X125176Y463047D01*
X124968Y463255D01*
X124843Y463588D01*
X124801Y463880D01*
G01X132383Y480700D02*
Y483200D01*
X131342D01*
X131008Y483075D01*
X130800Y482908D01*
X130717Y482575D01*
X130800Y482242D01*
X131050Y482033D01*
X131342Y481908D01*
X132383D01*
G01X131342D02*
X130717Y480700D01*
G01X128533D02*
X128450Y481242D01*
X128325Y481700D01*
X128158Y482117D01*
X127950Y482575D01*
X127617Y483200D01*
X129283D01*
G01X125350Y480700D02*
X125058Y480742D01*
X124725Y480867D01*
X124517Y481075D01*
X124433Y481367D01*
X124517Y481658D01*
X124767Y481908D01*
X125142Y482033D01*
X125558D01*
X125808Y482117D01*
X126017Y482325D01*
X126100Y482617D01*
X125975Y482908D01*
X125683Y483117D01*
X125350Y483200D01*
X125017Y483117D01*
X124725Y482908D01*
X124600Y482617D01*
X124683Y482325D01*
X124892Y482117D01*
X125142Y482033D01*
X125558D01*
X125933Y481908D01*
X126183Y481658D01*
X126267Y481367D01*
X126183Y481075D01*
X125975Y480867D01*
X125642Y480742D01*
X125350Y480700D01*
G01X122250Y483200D02*
X122583Y483117D01*
X122833Y482908D01*
X123000Y482658D01*
X123125Y482325D01*
X123167Y481950D01*
X123125Y481575D01*
X123000Y481242D01*
X122833Y480992D01*
X122583Y480783D01*
X122250Y480700D01*
X121917Y480783D01*
X121667Y480992D01*
X121500Y481242D01*
X121375Y481575D01*
X121333Y481950D01*
X121375Y482325D01*
X121500Y482658D01*
X121667Y482908D01*
X121917Y483117D01*
X122250Y483200D01*
G01X135000Y477700D02*
Y481700D01*
X142400D01*
G01X132183Y484900D02*
Y487400D01*
X131142D01*
X130808Y487275D01*
X130600Y487108D01*
X130517Y486775D01*
X130600Y486442D01*
X130850Y486233D01*
X131142Y486108D01*
X132183D01*
G01X131142D02*
X130517Y484900D01*
G01X128333D02*
X128250Y485442D01*
X128125Y485900D01*
X127958Y486317D01*
X127750Y486775D01*
X127417Y487400D01*
X129083D01*
G01X125942Y485942D02*
X125650Y486233D01*
X125400Y486400D01*
X125067Y486483D01*
X124775Y486400D01*
X124567Y486233D01*
X124400Y485983D01*
X124358Y485692D01*
X124400Y485442D01*
X124567Y485192D01*
X124817Y484983D01*
X125108Y484900D01*
X125442Y484983D01*
X125733Y485233D01*
X125900Y485608D01*
X125942Y486025D01*
X125858Y486567D01*
X125733Y486858D01*
X125525Y487150D01*
X125233Y487358D01*
X124942Y487400D01*
X124650Y487317D01*
X124442Y487108D01*
G01X122133Y484900D02*
X122050Y485442D01*
X121925Y485900D01*
X121758Y486317D01*
X121550Y486775D01*
X121217Y487400D01*
X122883D01*
G01X135000Y481900D02*
Y485900D01*
X142400D01*
G01X140567Y494500D02*
Y492708D01*
X140400Y492333D01*
X140067Y492083D01*
X139650Y492000D01*
X139233Y492083D01*
X138900Y492333D01*
X138733Y492708D01*
Y494500D01*
G01X136550Y492000D02*
Y494500D01*
X137050Y494000D01*
G01Y492000D02*
X136050D01*
G01X133450Y494500D02*
X133783Y494417D01*
X134033Y494208D01*
X134200Y493958D01*
X134325Y493625D01*
X134367Y493250D01*
X134325Y492875D01*
X134200Y492542D01*
X134033Y492292D01*
X133783Y492083D01*
X133450Y492000D01*
X133117Y492083D01*
X132867Y492292D01*
X132700Y492542D01*
X132575Y492875D01*
X132533Y493250D01*
X132575Y493625D01*
X132700Y493958D01*
X132867Y494208D01*
X133117Y494417D01*
X133450Y494500D01*
G01X129850Y492000D02*
Y494500D01*
X131392Y492708D01*
X129308D01*
G01X114463Y567205D02*
X114588Y566955D01*
X114671Y566663D01*
Y566330D01*
X114546Y565955D01*
X114338Y565663D01*
X114088Y565455D01*
X113671Y565288D01*
X113296Y565246D01*
X112921Y565330D01*
X112671Y565455D01*
X112421Y565705D01*
X112254Y565996D01*
X112171Y566288D01*
Y566580D01*
X112254Y566871D01*
X112379Y567121D01*
X112546Y567330D01*
G01X112171Y569305D02*
X112713Y569388D01*
X113171Y569513D01*
X113588Y569680D01*
X114046Y569888D01*
X114671Y570221D01*
Y568555D01*
G01Y572488D02*
X114588Y572155D01*
X114379Y571905D01*
X114129Y571738D01*
X113796Y571613D01*
X113421Y571571D01*
X113046Y571613D01*
X112713Y571738D01*
X112463Y571905D01*
X112254Y572155D01*
X112171Y572488D01*
X112254Y572821D01*
X112463Y573071D01*
X112713Y573238D01*
X113046Y573363D01*
X113421Y573405D01*
X113796Y573363D01*
X114129Y573238D01*
X114379Y573071D01*
X114588Y572821D01*
X114671Y572488D01*
G01X110763Y567205D02*
X110888Y566955D01*
X110971Y566663D01*
Y566330D01*
X110846Y565955D01*
X110638Y565663D01*
X110388Y565455D01*
X109971Y565288D01*
X109596Y565246D01*
X109221Y565330D01*
X108971Y565455D01*
X108721Y565705D01*
X108554Y565996D01*
X108471Y566288D01*
Y566580D01*
X108554Y566871D01*
X108679Y567121D01*
X108846Y567330D01*
G01X109513Y568596D02*
X109804Y568888D01*
X109971Y569138D01*
X110054Y569471D01*
X109971Y569763D01*
X109804Y569971D01*
X109554Y570138D01*
X109263Y570180D01*
X109013Y570138D01*
X108763Y569971D01*
X108554Y569721D01*
X108471Y569430D01*
X108554Y569096D01*
X108804Y568805D01*
X109179Y568638D01*
X109596Y568596D01*
X110138Y568680D01*
X110429Y568805D01*
X110721Y569013D01*
X110929Y569305D01*
X110971Y569596D01*
X110888Y569888D01*
X110679Y570096D01*
G01X108763Y571780D02*
X108554Y572071D01*
X108471Y572405D01*
X108554Y572738D01*
X108804Y573030D01*
X109179Y573238D01*
X109554Y573321D01*
X110013D01*
X110388Y573238D01*
X110721Y573030D01*
X110888Y572780D01*
X110971Y572488D01*
X110888Y572155D01*
X110721Y571905D01*
X110471Y571738D01*
X110138Y571655D01*
X109846Y571738D01*
X109554Y571946D01*
X109388Y572196D01*
X109346Y572488D01*
X109429Y572821D01*
X109638Y573071D01*
X110013Y573321D01*
G01X107063Y567205D02*
X107188Y566955D01*
X107271Y566663D01*
Y566330D01*
X107146Y565955D01*
X106938Y565663D01*
X106688Y565455D01*
X106271Y565288D01*
X105896Y565246D01*
X105521Y565330D01*
X105271Y565455D01*
X105021Y565705D01*
X104854Y565996D01*
X104771Y566288D01*
Y566580D01*
X104854Y566871D01*
X104979Y567121D01*
X105146Y567330D01*
G01X105813Y568596D02*
X106104Y568888D01*
X106271Y569138D01*
X106354Y569471D01*
X106271Y569763D01*
X106104Y569971D01*
X105854Y570138D01*
X105563Y570180D01*
X105313Y570138D01*
X105063Y569971D01*
X104854Y569721D01*
X104771Y569430D01*
X104854Y569096D01*
X105104Y568805D01*
X105479Y568638D01*
X105896Y568596D01*
X106438Y568680D01*
X106729Y568805D01*
X107021Y569013D01*
X107229Y569305D01*
X107271Y569596D01*
X107188Y569888D01*
X106979Y570096D01*
G01X104771Y572405D02*
X105313Y572488D01*
X105771Y572613D01*
X106188Y572780D01*
X106646Y572988D01*
X107271Y573321D01*
Y571655D01*
G01X126457Y509367D02*
X126707Y509492D01*
X126999Y509575D01*
X127332D01*
X127707Y509450D01*
X127999Y509242D01*
X128207Y508992D01*
X128374Y508575D01*
X128416Y508200D01*
X128332Y507825D01*
X128207Y507575D01*
X127957Y507325D01*
X127666Y507158D01*
X127374Y507075D01*
X127082D01*
X126791Y507158D01*
X126541Y507283D01*
X126332Y507450D01*
G01X125191D02*
X124941Y507242D01*
X124649Y507117D01*
X124274Y507075D01*
X123899Y507158D01*
X123607Y507325D01*
X123399Y507617D01*
X123357Y507950D01*
X123441Y508283D01*
X123649Y508492D01*
X123941Y508658D01*
X124232Y508700D01*
X124524Y508658D01*
X124899Y508492D01*
X124774Y509575D01*
X123649D01*
G01X121174D02*
X121507Y509492D01*
X121757Y509283D01*
X121924Y509033D01*
X122049Y508700D01*
X122091Y508325D01*
X122049Y507950D01*
X121924Y507617D01*
X121757Y507367D01*
X121507Y507158D01*
X121174Y507075D01*
X120841Y507158D01*
X120591Y507367D01*
X120424Y507617D01*
X120299Y507950D01*
X120257Y508325D01*
X120299Y508700D01*
X120424Y509033D01*
X120591Y509283D01*
X120841Y509492D01*
X121174Y509575D01*
G01X118074Y507075D02*
X117782Y507117D01*
X117449Y507242D01*
X117241Y507450D01*
X117157Y507742D01*
X117241Y508033D01*
X117491Y508283D01*
X117866Y508408D01*
X118282D01*
X118532Y508492D01*
X118741Y508700D01*
X118824Y508992D01*
X118699Y509283D01*
X118407Y509492D01*
X118074Y509575D01*
X117741Y509492D01*
X117449Y509283D01*
X117324Y508992D01*
X117407Y508700D01*
X117616Y508492D01*
X117866Y508408D01*
X118282D01*
X118657Y508283D01*
X118907Y508033D01*
X118991Y507742D01*
X118907Y507450D01*
X118699Y507242D01*
X118366Y507117D01*
X118074Y507075D01*
G01X117792Y547017D02*
X117917Y546767D01*
X118000Y546475D01*
Y546142D01*
X117875Y545767D01*
X117667Y545475D01*
X117417Y545267D01*
X117000Y545100D01*
X116625Y545058D01*
X116250Y545142D01*
X116000Y545267D01*
X115750Y545517D01*
X115583Y545808D01*
X115500Y546100D01*
Y546392D01*
X115583Y546683D01*
X115708Y546933D01*
X115875Y547142D01*
G01X115500Y549200D02*
X118000D01*
X117500Y548700D01*
G01X115500D02*
Y549700D01*
G01X118000Y552300D02*
X117917Y551967D01*
X117708Y551717D01*
X117458Y551550D01*
X117125Y551425D01*
X116750Y551383D01*
X116375Y551425D01*
X116042Y551550D01*
X115792Y551717D01*
X115583Y551967D01*
X115500Y552300D01*
X115583Y552633D01*
X115792Y552883D01*
X116042Y553050D01*
X116375Y553175D01*
X116750Y553217D01*
X117125Y553175D01*
X117458Y553050D01*
X117708Y552883D01*
X117917Y552633D01*
X118000Y552300D01*
G01X116542Y554608D02*
X116833Y554900D01*
X117000Y555150D01*
X117083Y555483D01*
X117000Y555775D01*
X116833Y555983D01*
X116583Y556150D01*
X116292Y556192D01*
X116042Y556150D01*
X115792Y555983D01*
X115583Y555733D01*
X115500Y555442D01*
X115583Y555108D01*
X115833Y554817D01*
X116208Y554650D01*
X116625Y554608D01*
X117167Y554692D01*
X117458Y554817D01*
X117750Y555025D01*
X117958Y555317D01*
X118000Y555608D01*
X117917Y555900D01*
X117708Y556108D01*
G01X83925Y556363D02*
Y552363D01*
X76525D01*
G01X83924Y560398D02*
Y556398D01*
X76524D01*
G01X112983Y549500D02*
Y552000D01*
X111942D01*
X111608Y551875D01*
X111400Y551708D01*
X111317Y551375D01*
X111400Y551042D01*
X111650Y550833D01*
X111942Y550708D01*
X112983D01*
G01X111942D02*
X111317Y549500D01*
G01X109842Y551583D02*
X109592Y551833D01*
X109300Y551958D01*
X108967Y552000D01*
X108550Y551917D01*
X108258Y551708D01*
X108175Y551458D01*
X108217Y551208D01*
X108383Y551000D01*
X109217Y550583D01*
X109592Y550292D01*
X109842Y549875D01*
X109925Y549500D01*
X108175D01*
G01X106742Y551583D02*
X106492Y551833D01*
X106200Y551958D01*
X105867Y552000D01*
X105450Y551917D01*
X105158Y551708D01*
X105075Y551458D01*
X105117Y551208D01*
X105283Y551000D01*
X106117Y550583D01*
X106492Y550292D01*
X106742Y549875D01*
X106825Y549500D01*
X105075D01*
G01X103767Y550000D02*
X103517Y549708D01*
X103183Y549542D01*
X102808Y549500D01*
X102475Y549542D01*
X102142Y549750D01*
X101933Y550000D01*
X101892Y550250D01*
X101975Y550542D01*
X102267Y550750D01*
X102558Y550833D01*
X102933D01*
G01X102558D02*
X102308Y550958D01*
X102100Y551167D01*
X102017Y551417D01*
X102100Y551667D01*
X102308Y551875D01*
X102683Y552000D01*
X103058Y551958D01*
X103433Y551792D01*
G01X103444Y557240D02*
Y553240D01*
X96044D01*
G01X115593Y561077D02*
Y563577D01*
X114552D01*
X114218Y563452D01*
X114010Y563285D01*
X113927Y562952D01*
X114010Y562619D01*
X114260Y562410D01*
X114552Y562285D01*
X115593D01*
G01X114552D02*
X113927Y561077D01*
G01X112452Y563160D02*
X112202Y563410D01*
X111910Y563535D01*
X111577Y563577D01*
X111160Y563494D01*
X110868Y563285D01*
X110785Y563035D01*
X110827Y562785D01*
X110993Y562577D01*
X111827Y562160D01*
X112202Y561869D01*
X112452Y561452D01*
X112535Y561077D01*
X110785D01*
G01X109352Y563160D02*
X109102Y563410D01*
X108810Y563535D01*
X108477Y563577D01*
X108060Y563494D01*
X107768Y563285D01*
X107685Y563035D01*
X107727Y562785D01*
X107893Y562577D01*
X108727Y562160D01*
X109102Y561869D01*
X109352Y561452D01*
X109435Y561077D01*
X107685D01*
G01X106252Y563160D02*
X106002Y563410D01*
X105710Y563535D01*
X105377Y563577D01*
X104960Y563494D01*
X104668Y563285D01*
X104585Y563035D01*
X104627Y562785D01*
X104793Y562577D01*
X105627Y562160D01*
X106002Y561869D01*
X106252Y561452D01*
X106335Y561077D01*
X104585D01*
G01X103476Y562166D02*
Y558166D01*
X96076D01*
G01X113000Y521517D02*
X115500D01*
Y522558D01*
X115375Y522892D01*
X115208Y523100D01*
X114875Y523183D01*
X114542Y523100D01*
X114333Y522850D01*
X114208Y522558D01*
Y521517D01*
G01Y522558D02*
X113000Y523183D01*
G01X115083Y524658D02*
X115333Y524908D01*
X115458Y525200D01*
X115500Y525533D01*
X115417Y525950D01*
X115208Y526242D01*
X114958Y526325D01*
X114708Y526283D01*
X114500Y526117D01*
X114083Y525283D01*
X113792Y524908D01*
X113375Y524658D01*
X113000Y524575D01*
Y526325D01*
G01Y528467D02*
X113542Y528550D01*
X114000Y528675D01*
X114417Y528842D01*
X114875Y529050D01*
X115500Y529383D01*
Y527717D01*
G01X113000Y531567D02*
X113542Y531650D01*
X114000Y531775D01*
X114417Y531942D01*
X114875Y532150D01*
X115500Y532483D01*
Y530817D01*
G01X131983Y528500D02*
Y531000D01*
X130942D01*
X130608Y530875D01*
X130400Y530708D01*
X130317Y530375D01*
X130400Y530042D01*
X130650Y529833D01*
X130942Y529708D01*
X131983D01*
G01X130942D02*
X130317Y528500D01*
G01X128967Y529000D02*
X128717Y528708D01*
X128383Y528542D01*
X128008Y528500D01*
X127675Y528542D01*
X127342Y528750D01*
X127133Y529000D01*
X127092Y529250D01*
X127175Y529542D01*
X127467Y529750D01*
X127758Y529833D01*
X128133D01*
G01X127758D02*
X127508Y529958D01*
X127300Y530167D01*
X127217Y530417D01*
X127300Y530667D01*
X127508Y530875D01*
X127883Y531000D01*
X128258Y530958D01*
X128633Y530792D01*
G01X125033Y528500D02*
X124950Y529042D01*
X124825Y529500D01*
X124658Y529917D01*
X124450Y530375D01*
X124117Y531000D01*
X125783D01*
G01X122767Y528875D02*
X122517Y528667D01*
X122225Y528542D01*
X121850Y528500D01*
X121475Y528583D01*
X121183Y528750D01*
X120975Y529042D01*
X120933Y529375D01*
X121017Y529708D01*
X121225Y529917D01*
X121517Y530083D01*
X121808Y530125D01*
X122100Y530083D01*
X122475Y529917D01*
X122350Y531000D01*
X121225D01*
G01X136900Y529517D02*
X139400D01*
Y530558D01*
X139275Y530892D01*
X139108Y531100D01*
X138775Y531183D01*
X138442Y531100D01*
X138233Y530850D01*
X138108Y530558D01*
Y529517D01*
G01Y530558D02*
X136900Y531183D01*
G01X137400Y532533D02*
X137108Y532783D01*
X136942Y533117D01*
X136900Y533492D01*
X136942Y533825D01*
X137150Y534158D01*
X137400Y534367D01*
X137650Y534408D01*
X137942Y534325D01*
X138150Y534033D01*
X138233Y533742D01*
Y533367D01*
G01Y533742D02*
X138358Y533992D01*
X138567Y534200D01*
X138817Y534283D01*
X139067Y534200D01*
X139275Y533992D01*
X139400Y533617D01*
X139358Y533242D01*
X139192Y532867D01*
G01X136900Y536467D02*
X137442Y536550D01*
X137900Y536675D01*
X138317Y536842D01*
X138775Y537050D01*
X139400Y537383D01*
Y535717D01*
G01X136900Y540150D02*
X139400D01*
X137608Y538608D01*
Y540692D01*
G01X133200Y529517D02*
X135700D01*
Y530558D01*
X135575Y530892D01*
X135408Y531100D01*
X135075Y531183D01*
X134742Y531100D01*
X134533Y530850D01*
X134408Y530558D01*
Y529517D01*
G01Y530558D02*
X133200Y531183D01*
G01X133700Y532533D02*
X133408Y532783D01*
X133242Y533117D01*
X133200Y533492D01*
X133242Y533825D01*
X133450Y534158D01*
X133700Y534367D01*
X133950Y534408D01*
X134242Y534325D01*
X134450Y534033D01*
X134533Y533742D01*
Y533367D01*
G01Y533742D02*
X134658Y533992D01*
X134867Y534200D01*
X135117Y534283D01*
X135367Y534200D01*
X135575Y533992D01*
X135700Y533617D01*
X135658Y533242D01*
X135492Y532867D01*
G01X133200Y536467D02*
X133742Y536550D01*
X134200Y536675D01*
X134617Y536842D01*
X135075Y537050D01*
X135700Y537383D01*
Y535717D01*
G01X133700Y538733D02*
X133408Y538983D01*
X133242Y539317D01*
X133200Y539692D01*
X133242Y540025D01*
X133450Y540358D01*
X133700Y540567D01*
X133950Y540608D01*
X134242Y540525D01*
X134450Y540233D01*
X134533Y539942D01*
Y539567D01*
G01Y539942D02*
X134658Y540192D01*
X134867Y540400D01*
X135117Y540483D01*
X135367Y540400D01*
X135575Y540192D01*
X135700Y539817D01*
X135658Y539442D01*
X135492Y539067D01*
G01X130783Y524300D02*
Y526800D01*
X129742D01*
X129408Y526675D01*
X129200Y526508D01*
X129117Y526175D01*
X129200Y525842D01*
X129450Y525633D01*
X129742Y525508D01*
X130783D01*
G01X129742D02*
X129117Y524300D01*
G01X127767Y524800D02*
X127517Y524508D01*
X127183Y524342D01*
X126808Y524300D01*
X126475Y524342D01*
X126142Y524550D01*
X125933Y524800D01*
X125892Y525050D01*
X125975Y525342D01*
X126267Y525550D01*
X126558Y525633D01*
X126933D01*
G01X126558D02*
X126308Y525758D01*
X126100Y525967D01*
X126017Y526217D01*
X126100Y526467D01*
X126308Y526675D01*
X126683Y526800D01*
X127058Y526758D01*
X127433Y526592D01*
G01X123833Y524300D02*
X123750Y524842D01*
X123625Y525300D01*
X123458Y525717D01*
X123250Y526175D01*
X122917Y526800D01*
X124583D01*
G01X120650D02*
X120983Y526717D01*
X121233Y526508D01*
X121400Y526258D01*
X121525Y525925D01*
X121567Y525550D01*
X121525Y525175D01*
X121400Y524842D01*
X121233Y524592D01*
X120983Y524383D01*
X120650Y524300D01*
X120317Y524383D01*
X120067Y524592D01*
X119900Y524842D01*
X119775Y525175D01*
X119733Y525550D01*
X119775Y525925D01*
X119900Y526258D01*
X120067Y526508D01*
X120317Y526717D01*
X120650Y526800D01*
G01X143983Y508500D02*
Y511000D01*
X142942D01*
X142608Y510875D01*
X142400Y510708D01*
X142317Y510375D01*
X142400Y510042D01*
X142650Y509833D01*
X142942Y509708D01*
X143983D01*
G01X142942D02*
X142317Y508500D01*
G01X140967Y508875D02*
X140717Y508667D01*
X140425Y508542D01*
X140050Y508500D01*
X139675Y508583D01*
X139383Y508750D01*
X139175Y509042D01*
X139133Y509375D01*
X139217Y509708D01*
X139425Y509917D01*
X139717Y510083D01*
X140008Y510125D01*
X140300Y510083D01*
X140675Y509917D01*
X140550Y511000D01*
X139425D01*
G01X136950D02*
X137283Y510917D01*
X137533Y510708D01*
X137700Y510458D01*
X137825Y510125D01*
X137867Y509750D01*
X137825Y509375D01*
X137700Y509042D01*
X137533Y508792D01*
X137283Y508583D01*
X136950Y508500D01*
X136617Y508583D01*
X136367Y508792D01*
X136200Y509042D01*
X136075Y509375D01*
X136033Y509750D01*
X136075Y510125D01*
X136200Y510458D01*
X136367Y510708D01*
X136617Y510917D01*
X136950Y511000D01*
G01X133850Y508500D02*
Y511000D01*
X134350Y510500D01*
G01Y508500D02*
X133350D01*
G01X112357Y501580D02*
X114857D01*
Y502621D01*
X114732Y502955D01*
X114565Y503163D01*
X114232Y503246D01*
X113899Y503163D01*
X113690Y502913D01*
X113565Y502621D01*
Y501580D01*
G01Y502621D02*
X112357Y503246D01*
G01Y505430D02*
X112899Y505513D01*
X113357Y505638D01*
X113774Y505805D01*
X114232Y506013D01*
X114857Y506346D01*
Y504680D01*
G01X112357Y508613D02*
X114857D01*
X114357Y508113D01*
G01X112357D02*
Y509113D01*
G01X113399Y510921D02*
X113690Y511213D01*
X113857Y511463D01*
X113940Y511796D01*
X113857Y512088D01*
X113690Y512296D01*
X113440Y512463D01*
X113149Y512505D01*
X112899Y512463D01*
X112649Y512296D01*
X112440Y512046D01*
X112357Y511755D01*
X112440Y511421D01*
X112690Y511130D01*
X113065Y510963D01*
X113482Y510921D01*
X114024Y511005D01*
X114315Y511130D01*
X114607Y511338D01*
X114815Y511630D01*
X114857Y511921D01*
X114774Y512213D01*
X114565Y512421D01*
G01X122273Y495359D02*
X118273D01*
Y502759D01*
G01X109183Y494712D02*
Y497212D01*
X108142D01*
X107808Y497087D01*
X107600Y496920D01*
X107517Y496587D01*
X107600Y496254D01*
X107850Y496045D01*
X108142Y495920D01*
X109183D01*
G01X108142D02*
X107517Y494712D01*
G01X105333D02*
X105250Y495254D01*
X105125Y495712D01*
X104958Y496129D01*
X104750Y496587D01*
X104417Y497212D01*
X106083D01*
G01X102150Y494712D02*
X101858Y494754D01*
X101525Y494879D01*
X101317Y495087D01*
X101233Y495379D01*
X101317Y495670D01*
X101567Y495920D01*
X101942Y496045D01*
X102358D01*
X102608Y496129D01*
X102817Y496337D01*
X102900Y496629D01*
X102775Y496920D01*
X102483Y497129D01*
X102150Y497212D01*
X101817Y497129D01*
X101525Y496920D01*
X101400Y496629D01*
X101483Y496337D01*
X101692Y496129D01*
X101942Y496045D01*
X102358D01*
X102733Y495920D01*
X102983Y495670D01*
X103067Y495379D01*
X102983Y495087D01*
X102775Y494879D01*
X102442Y494754D01*
X102150Y494712D01*
G01X99967Y495212D02*
X99717Y494920D01*
X99383Y494754D01*
X99008Y494712D01*
X98675Y494754D01*
X98342Y494962D01*
X98133Y495212D01*
X98092Y495462D01*
X98175Y495754D01*
X98467Y495962D01*
X98758Y496045D01*
X99133D01*
G01X98758D02*
X98508Y496170D01*
X98300Y496379D01*
X98217Y496629D01*
X98300Y496879D01*
X98508Y497087D01*
X98883Y497212D01*
X99258Y497170D01*
X99633Y497004D01*
G01X110772Y495305D02*
Y499305D01*
X118172D01*
G01X88659Y512077D02*
X84659D01*
Y519477D01*
G01X88673Y504600D02*
X84673D01*
Y512000D01*
G01X83032Y512077D02*
X79032D01*
Y519477D01*
G01X83068Y504466D02*
X79068D01*
Y511866D01*
G01X94286Y512077D02*
X90286D01*
Y519477D01*
G01X94273Y504600D02*
X90273D01*
Y512000D01*
G01X99913Y512077D02*
X95913D01*
Y519477D01*
G01X99900Y504600D02*
X95900D01*
Y512000D01*
G01X77405Y512077D02*
X73405D01*
Y519477D01*
G01X77373Y504479D02*
X73373D01*
Y511879D01*
G01X140500Y513017D02*
X143000D01*
Y514058D01*
X142875Y514392D01*
X142708Y514600D01*
X142375Y514683D01*
X142042Y514600D01*
X141833Y514350D01*
X141708Y514058D01*
Y513017D01*
G01Y514058D02*
X140500Y514683D01*
G01Y517450D02*
X143000D01*
X141208Y515908D01*
Y517992D01*
G01X140500Y520050D02*
X143000D01*
X142500Y519550D01*
G01X140500D02*
Y520550D01*
G01X141542Y522358D02*
X141833Y522650D01*
X142000Y522900D01*
X142083Y523233D01*
X142000Y523525D01*
X141833Y523733D01*
X141583Y523900D01*
X141292Y523942D01*
X141042Y523900D01*
X140792Y523733D01*
X140583Y523483D01*
X140500Y523192D01*
X140583Y522858D01*
X140833Y522567D01*
X141208Y522400D01*
X141625Y522358D01*
X142167Y522442D01*
X142458Y522567D01*
X142750Y522775D01*
X142958Y523067D01*
X143000Y523358D01*
X142917Y523650D01*
X142708Y523858D01*
G01X131150Y535000D02*
Y532500D01*
G01X132108Y535000D02*
X130192D01*
G01X128883Y532500D02*
Y535000D01*
X127883D01*
X127550Y534875D01*
X127300Y534583D01*
X127217Y534250D01*
X127300Y533917D01*
X127508Y533667D01*
X127883Y533542D01*
X128883D01*
G01X124950Y532500D02*
Y535000D01*
X125450Y534500D01*
G01Y532500D02*
X124450D01*
G01X121850D02*
X121558Y532542D01*
X121225Y532667D01*
X121017Y532875D01*
X120933Y533167D01*
X121017Y533458D01*
X121267Y533708D01*
X121642Y533833D01*
X122058D01*
X122308Y533917D01*
X122517Y534125D01*
X122600Y534417D01*
X122475Y534708D01*
X122183Y534917D01*
X121850Y535000D01*
X121517Y534917D01*
X121225Y534708D01*
X121100Y534417D01*
X121183Y534125D01*
X121392Y533917D01*
X121642Y533833D01*
X122058D01*
X122433Y533708D01*
X122683Y533458D01*
X122767Y533167D01*
X122683Y532875D01*
X122475Y532667D01*
X122142Y532542D01*
X121850Y532500D01*
G01X130600Y496100D02*
X144000D01*
G01X130600Y506100D02*
Y496100D01*
G01X144000Y506100D02*
X130600D01*
G01X126292Y547067D02*
X126417Y546817D01*
X126500Y546525D01*
Y546192D01*
X126375Y545817D01*
X126167Y545525D01*
X125917Y545317D01*
X125500Y545150D01*
X125125Y545108D01*
X124750Y545192D01*
X124500Y545317D01*
X124250Y545567D01*
X124083Y545858D01*
X124000Y546150D01*
Y546442D01*
X124083Y546733D01*
X124208Y546983D01*
X124375Y547192D01*
G01X124292Y548542D02*
X124083Y548833D01*
X124000Y549167D01*
X124083Y549500D01*
X124333Y549792D01*
X124708Y550000D01*
X125083Y550083D01*
X125542D01*
X125917Y550000D01*
X126250Y549792D01*
X126417Y549542D01*
X126500Y549250D01*
X126417Y548917D01*
X126250Y548667D01*
X126000Y548500D01*
X125667Y548417D01*
X125375Y548500D01*
X125083Y548708D01*
X124917Y548958D01*
X124875Y549250D01*
X124958Y549583D01*
X125167Y549833D01*
X125542Y550083D01*
G01X124292Y551642D02*
X124083Y551933D01*
X124000Y552267D01*
X124083Y552600D01*
X124333Y552892D01*
X124708Y553100D01*
X125083Y553183D01*
X125542D01*
X125917Y553100D01*
X126250Y552892D01*
X126417Y552642D01*
X126500Y552350D01*
X126417Y552017D01*
X126250Y551767D01*
X126000Y551600D01*
X125667Y551517D01*
X125375Y551600D01*
X125083Y551808D01*
X124917Y552058D01*
X124875Y552350D01*
X124958Y552683D01*
X125167Y552933D01*
X125542Y553183D01*
G01X130792Y547067D02*
X130917Y546817D01*
X131000Y546525D01*
Y546192D01*
X130875Y545817D01*
X130667Y545525D01*
X130417Y545317D01*
X130000Y545150D01*
X129625Y545108D01*
X129250Y545192D01*
X129000Y545317D01*
X128750Y545567D01*
X128583Y545858D01*
X128500Y546150D01*
Y546442D01*
X128583Y546733D01*
X128708Y546983D01*
X128875Y547192D01*
G01X128792Y548542D02*
X128583Y548833D01*
X128500Y549167D01*
X128583Y549500D01*
X128833Y549792D01*
X129208Y550000D01*
X129583Y550083D01*
X130042D01*
X130417Y550000D01*
X130750Y549792D01*
X130917Y549542D01*
X131000Y549250D01*
X130917Y548917D01*
X130750Y548667D01*
X130500Y548500D01*
X130167Y548417D01*
X129875Y548500D01*
X129583Y548708D01*
X129417Y548958D01*
X129375Y549250D01*
X129458Y549583D01*
X129667Y549833D01*
X130042Y550083D01*
G01X128500Y552267D02*
X129042Y552350D01*
X129500Y552475D01*
X129917Y552642D01*
X130375Y552850D01*
X131000Y553183D01*
Y551517D01*
G01X103183Y541792D02*
X103433Y541917D01*
X103725Y542000D01*
X104058D01*
X104433Y541875D01*
X104725Y541667D01*
X104933Y541417D01*
X105100Y541000D01*
X105142Y540625D01*
X105058Y540250D01*
X104933Y540000D01*
X104683Y539750D01*
X104392Y539583D01*
X104100Y539500D01*
X103808D01*
X103517Y539583D01*
X103267Y539708D01*
X103058Y539875D01*
G01X101792Y540542D02*
X101500Y540833D01*
X101250Y541000D01*
X100917Y541083D01*
X100625Y541000D01*
X100417Y540833D01*
X100250Y540583D01*
X100208Y540292D01*
X100250Y540042D01*
X100417Y539792D01*
X100667Y539583D01*
X100958Y539500D01*
X101292Y539583D01*
X101583Y539833D01*
X101750Y540208D01*
X101792Y540625D01*
X101708Y541167D01*
X101583Y541458D01*
X101375Y541750D01*
X101083Y541958D01*
X100792Y542000D01*
X100500Y541917D01*
X100292Y541708D01*
G01X97400Y539500D02*
Y542000D01*
X98942Y540208D01*
X96858D01*
G01X122292Y547017D02*
X122417Y546767D01*
X122500Y546475D01*
Y546142D01*
X122375Y545767D01*
X122167Y545475D01*
X121917Y545267D01*
X121500Y545100D01*
X121125Y545058D01*
X120750Y545142D01*
X120500Y545267D01*
X120250Y545517D01*
X120083Y545808D01*
X120000Y546100D01*
Y546392D01*
X120083Y546683D01*
X120208Y546933D01*
X120375Y547142D01*
G01X120000Y549200D02*
X122500D01*
X122000Y548700D01*
G01X120000D02*
Y549700D01*
G01X122500Y552300D02*
X122417Y551967D01*
X122208Y551717D01*
X121958Y551550D01*
X121625Y551425D01*
X121250Y551383D01*
X120875Y551425D01*
X120542Y551550D01*
X120292Y551717D01*
X120083Y551967D01*
X120000Y552300D01*
X120083Y552633D01*
X120292Y552883D01*
X120542Y553050D01*
X120875Y553175D01*
X121250Y553217D01*
X121625Y553175D01*
X121958Y553050D01*
X122208Y552883D01*
X122417Y552633D01*
X122500Y552300D01*
G01X120000Y555900D02*
X122500D01*
X120708Y554358D01*
Y556442D01*
G01X112959Y592717D02*
X113084Y592467D01*
X113167Y592175D01*
Y591842D01*
X113042Y591467D01*
X112834Y591175D01*
X112584Y590967D01*
X112167Y590800D01*
X111792Y590758D01*
X111417Y590842D01*
X111167Y590967D01*
X110917Y591217D01*
X110750Y591508D01*
X110667Y591800D01*
Y592092D01*
X110750Y592383D01*
X110875Y592633D01*
X111042Y592842D01*
G01X110959Y594192D02*
X110750Y594483D01*
X110667Y594817D01*
X110750Y595150D01*
X111000Y595442D01*
X111375Y595650D01*
X111750Y595733D01*
X112209D01*
X112584Y595650D01*
X112917Y595442D01*
X113084Y595192D01*
X113167Y594900D01*
X113084Y594567D01*
X112917Y594317D01*
X112667Y594150D01*
X112334Y594067D01*
X112042Y594150D01*
X111750Y594358D01*
X111584Y594608D01*
X111542Y594900D01*
X111625Y595233D01*
X111834Y595483D01*
X112209Y595733D01*
G01X110667Y598500D02*
X113167D01*
X111375Y596958D01*
Y599042D01*
G01X108959Y592717D02*
X109084Y592467D01*
X109167Y592175D01*
Y591842D01*
X109042Y591467D01*
X108834Y591175D01*
X108584Y590967D01*
X108167Y590800D01*
X107792Y590758D01*
X107417Y590842D01*
X107167Y590967D01*
X106917Y591217D01*
X106750Y591508D01*
X106667Y591800D01*
Y592092D01*
X106750Y592383D01*
X106875Y592633D01*
X107042Y592842D01*
G01X106959Y594192D02*
X106750Y594483D01*
X106667Y594817D01*
X106750Y595150D01*
X107000Y595442D01*
X107375Y595650D01*
X107750Y595733D01*
X108209D01*
X108584Y595650D01*
X108917Y595442D01*
X109084Y595192D01*
X109167Y594900D01*
X109084Y594567D01*
X108917Y594317D01*
X108667Y594150D01*
X108334Y594067D01*
X108042Y594150D01*
X107750Y594358D01*
X107584Y594608D01*
X107542Y594900D01*
X107625Y595233D01*
X107834Y595483D01*
X108209Y595733D01*
G01X107167Y597083D02*
X106875Y597333D01*
X106709Y597667D01*
X106667Y598042D01*
X106709Y598375D01*
X106917Y598708D01*
X107167Y598917D01*
X107417Y598958D01*
X107709Y598875D01*
X107917Y598583D01*
X108000Y598292D01*
Y597917D01*
G01Y598292D02*
X108125Y598542D01*
X108334Y598750D01*
X108584Y598833D01*
X108834Y598750D01*
X109042Y598542D01*
X109167Y598167D01*
X109125Y597792D01*
X108959Y597417D01*
G01X104516Y581202D02*
X104641Y580952D01*
X104724Y580660D01*
Y580327D01*
X104599Y579952D01*
X104391Y579660D01*
X104141Y579452D01*
X103724Y579285D01*
X103349Y579243D01*
X102974Y579327D01*
X102724Y579452D01*
X102474Y579702D01*
X102307Y579993D01*
X102224Y580285D01*
Y580577D01*
X102307Y580868D01*
X102432Y581118D01*
X102599Y581327D01*
G01X102224Y583302D02*
X102766Y583385D01*
X103224Y583510D01*
X103641Y583677D01*
X104099Y583885D01*
X104724Y584218D01*
Y582552D01*
G01X102724Y585568D02*
X102432Y585818D01*
X102266Y586152D01*
X102224Y586527D01*
X102266Y586860D01*
X102474Y587193D01*
X102724Y587402D01*
X102974Y587443D01*
X103266Y587360D01*
X103474Y587068D01*
X103557Y586777D01*
Y586402D01*
G01Y586777D02*
X103682Y587027D01*
X103891Y587235D01*
X104141Y587318D01*
X104391Y587235D01*
X104599Y587027D01*
X104724Y586652D01*
X104682Y586277D01*
X104516Y585902D01*
G01X100816Y581202D02*
X100941Y580952D01*
X101024Y580660D01*
Y580327D01*
X100899Y579952D01*
X100691Y579660D01*
X100441Y579452D01*
X100024Y579285D01*
X99649Y579243D01*
X99274Y579327D01*
X99024Y579452D01*
X98774Y579702D01*
X98607Y579993D01*
X98524Y580285D01*
Y580577D01*
X98607Y580868D01*
X98732Y581118D01*
X98899Y581327D01*
G01X98524Y583302D02*
X99066Y583385D01*
X99524Y583510D01*
X99941Y583677D01*
X100399Y583885D01*
X101024Y584218D01*
Y582552D01*
G01X100607Y585693D02*
X100857Y585943D01*
X100982Y586235D01*
X101024Y586568D01*
X100941Y586985D01*
X100732Y587277D01*
X100482Y587360D01*
X100232Y587318D01*
X100024Y587152D01*
X99607Y586318D01*
X99316Y585943D01*
X98899Y585693D01*
X98524Y585610D01*
Y587360D01*
G01X78292Y578817D02*
X78417Y578567D01*
X78500Y578275D01*
Y577942D01*
X78375Y577567D01*
X78167Y577275D01*
X77917Y577067D01*
X77500Y576900D01*
X77125Y576858D01*
X76750Y576942D01*
X76500Y577067D01*
X76250Y577317D01*
X76083Y577608D01*
X76000Y577900D01*
Y578192D01*
X76083Y578483D01*
X76208Y578733D01*
X76375Y578942D01*
G01X77042Y580208D02*
X77333Y580500D01*
X77500Y580750D01*
X77583Y581083D01*
X77500Y581375D01*
X77333Y581583D01*
X77083Y581750D01*
X76792Y581792D01*
X76542Y581750D01*
X76292Y581583D01*
X76083Y581333D01*
X76000Y581042D01*
X76083Y580708D01*
X76333Y580417D01*
X76708Y580250D01*
X77125Y580208D01*
X77667Y580292D01*
X77958Y580417D01*
X78250Y580625D01*
X78458Y580917D01*
X78500Y581208D01*
X78417Y581500D01*
X78208Y581708D01*
G01X77042Y583308D02*
X77333Y583600D01*
X77500Y583850D01*
X77583Y584183D01*
X77500Y584475D01*
X77333Y584683D01*
X77083Y584850D01*
X76792Y584892D01*
X76542Y584850D01*
X76292Y584683D01*
X76083Y584433D01*
X76000Y584142D01*
X76083Y583808D01*
X76333Y583517D01*
X76708Y583350D01*
X77125Y583308D01*
X77667Y583392D01*
X77958Y583517D01*
X78250Y583725D01*
X78458Y584017D01*
X78500Y584308D01*
X78417Y584600D01*
X78208Y584808D01*
G01X143292Y627767D02*
X143417Y627517D01*
X143500Y627225D01*
Y626892D01*
X143375Y626517D01*
X143167Y626225D01*
X142917Y626017D01*
X142500Y625850D01*
X142125Y625808D01*
X141750Y625892D01*
X141500Y626017D01*
X141250Y626267D01*
X141083Y626558D01*
X141000Y626850D01*
Y627142D01*
X141083Y627433D01*
X141208Y627683D01*
X141375Y627892D01*
G01Y629033D02*
X141167Y629283D01*
X141042Y629575D01*
X141000Y629950D01*
X141083Y630325D01*
X141250Y630617D01*
X141542Y630825D01*
X141875Y630867D01*
X142208Y630783D01*
X142417Y630575D01*
X142583Y630283D01*
X142625Y629992D01*
X142583Y629700D01*
X142417Y629325D01*
X143500Y629450D01*
Y630575D01*
G01X141000Y633050D02*
X143500D01*
X143000Y632550D01*
G01X141000D02*
Y633550D01*
G01X141292Y635442D02*
X141083Y635733D01*
X141000Y636067D01*
X141083Y636400D01*
X141333Y636692D01*
X141708Y636900D01*
X142083Y636983D01*
X142542D01*
X142917Y636900D01*
X143250Y636692D01*
X143417Y636442D01*
X143500Y636150D01*
X143417Y635817D01*
X143250Y635567D01*
X143000Y635400D01*
X142667Y635317D01*
X142375Y635400D01*
X142083Y635608D01*
X141917Y635858D01*
X141875Y636150D01*
X141958Y636483D01*
X142167Y636733D01*
X142542Y636983D01*
G01X127959Y573317D02*
X128084Y573067D01*
X128167Y572775D01*
Y572442D01*
X128042Y572067D01*
X127834Y571775D01*
X127584Y571567D01*
X127167Y571400D01*
X126792Y571358D01*
X126417Y571442D01*
X126167Y571567D01*
X125917Y571817D01*
X125750Y572108D01*
X125667Y572400D01*
Y572692D01*
X125750Y572983D01*
X125875Y573233D01*
X126042Y573442D01*
G01Y574583D02*
X125834Y574833D01*
X125709Y575125D01*
X125667Y575500D01*
X125750Y575875D01*
X125917Y576167D01*
X126209Y576375D01*
X126542Y576417D01*
X126875Y576333D01*
X127084Y576125D01*
X127250Y575833D01*
X127292Y575542D01*
X127250Y575250D01*
X127084Y574875D01*
X128167Y575000D01*
Y576125D01*
G01X125667Y578517D02*
X126209Y578600D01*
X126667Y578725D01*
X127084Y578892D01*
X127542Y579100D01*
X128167Y579433D01*
Y577767D01*
G01X83208Y569024D02*
Y571524D01*
X82167D01*
X81833Y571399D01*
X81625Y571232D01*
X81542Y570899D01*
X81625Y570566D01*
X81875Y570357D01*
X82167Y570232D01*
X83208D01*
G01X82167D02*
X81542Y569024D01*
G01X80067Y571107D02*
X79817Y571357D01*
X79525Y571482D01*
X79192Y571524D01*
X78775Y571441D01*
X78483Y571232D01*
X78400Y570982D01*
X78442Y570732D01*
X78608Y570524D01*
X79442Y570107D01*
X79817Y569816D01*
X80067Y569399D01*
X80150Y569024D01*
X78400D01*
G01X76175Y571524D02*
X76508Y571441D01*
X76758Y571232D01*
X76925Y570982D01*
X77050Y570649D01*
X77092Y570274D01*
X77050Y569899D01*
X76925Y569566D01*
X76758Y569316D01*
X76508Y569107D01*
X76175Y569024D01*
X75842Y569107D01*
X75592Y569316D01*
X75425Y569566D01*
X75300Y569899D01*
X75258Y570274D01*
X75300Y570649D01*
X75425Y570982D01*
X75592Y571232D01*
X75842Y571441D01*
X76175Y571524D01*
G01X73867Y570066D02*
X73575Y570357D01*
X73325Y570524D01*
X72992Y570607D01*
X72700Y570524D01*
X72492Y570357D01*
X72325Y570107D01*
X72283Y569816D01*
X72325Y569566D01*
X72492Y569316D01*
X72742Y569107D01*
X73033Y569024D01*
X73367Y569107D01*
X73658Y569357D01*
X73825Y569732D01*
X73867Y570149D01*
X73783Y570691D01*
X73658Y570982D01*
X73450Y571274D01*
X73158Y571482D01*
X72867Y571524D01*
X72575Y571441D01*
X72367Y571232D01*
G01X83207Y573059D02*
Y575559D01*
X82166D01*
X81832Y575434D01*
X81624Y575267D01*
X81541Y574934D01*
X81624Y574601D01*
X81874Y574392D01*
X82166Y574267D01*
X83207D01*
G01X82166D02*
X81541Y573059D01*
G01X80066Y575142D02*
X79816Y575392D01*
X79524Y575517D01*
X79191Y575559D01*
X78774Y575476D01*
X78482Y575267D01*
X78399Y575017D01*
X78441Y574767D01*
X78607Y574559D01*
X79441Y574142D01*
X79816Y573851D01*
X80066Y573434D01*
X80149Y573059D01*
X78399D01*
G01X76174Y575559D02*
X76507Y575476D01*
X76757Y575267D01*
X76924Y575017D01*
X77049Y574684D01*
X77091Y574309D01*
X77049Y573934D01*
X76924Y573601D01*
X76757Y573351D01*
X76507Y573142D01*
X76174Y573059D01*
X75841Y573142D01*
X75591Y573351D01*
X75424Y573601D01*
X75299Y573934D01*
X75257Y574309D01*
X75299Y574684D01*
X75424Y575017D01*
X75591Y575267D01*
X75841Y575476D01*
X76174Y575559D01*
G01X73991Y573434D02*
X73741Y573226D01*
X73449Y573101D01*
X73074Y573059D01*
X72699Y573142D01*
X72407Y573309D01*
X72199Y573601D01*
X72157Y573934D01*
X72241Y574267D01*
X72449Y574476D01*
X72741Y574642D01*
X73032Y574684D01*
X73324Y574642D01*
X73699Y574476D01*
X73574Y575559D01*
X72449D01*
G01X85114Y632326D02*
Y634826D01*
X84073D01*
X83739Y634701D01*
X83531Y634534D01*
X83448Y634201D01*
X83531Y633868D01*
X83781Y633659D01*
X84073Y633534D01*
X85114D01*
G01X84073D02*
X83448Y632326D01*
G01X81973Y634409D02*
X81723Y634659D01*
X81431Y634784D01*
X81098Y634826D01*
X80681Y634743D01*
X80389Y634534D01*
X80306Y634284D01*
X80348Y634034D01*
X80514Y633826D01*
X81348Y633409D01*
X81723Y633118D01*
X81973Y632701D01*
X82056Y632326D01*
X80306D01*
G01X78081Y634826D02*
X78414Y634743D01*
X78664Y634534D01*
X78831Y634284D01*
X78956Y633951D01*
X78998Y633576D01*
X78956Y633201D01*
X78831Y632868D01*
X78664Y632618D01*
X78414Y632409D01*
X78081Y632326D01*
X77748Y632409D01*
X77498Y632618D01*
X77331Y632868D01*
X77206Y633201D01*
X77164Y633576D01*
X77206Y633951D01*
X77331Y634284D01*
X77498Y634534D01*
X77748Y634743D01*
X78081Y634826D01*
G01X75773Y634409D02*
X75523Y634659D01*
X75231Y634784D01*
X74898Y634826D01*
X74481Y634743D01*
X74189Y634534D01*
X74106Y634284D01*
X74148Y634034D01*
X74314Y633826D01*
X75148Y633409D01*
X75523Y633118D01*
X75773Y632701D01*
X75856Y632326D01*
X74106D01*
G01X85126Y627871D02*
Y630371D01*
X84085D01*
X83751Y630246D01*
X83543Y630079D01*
X83460Y629746D01*
X83543Y629413D01*
X83793Y629204D01*
X84085Y629079D01*
X85126D01*
G01X84085D02*
X83460Y627871D01*
G01X81193D02*
Y630371D01*
X81693Y629871D01*
G01Y627871D02*
X80693D01*
G01X78801Y628163D02*
X78510Y627954D01*
X78176Y627871D01*
X77843Y627954D01*
X77551Y628204D01*
X77343Y628579D01*
X77260Y628954D01*
Y629413D01*
X77343Y629788D01*
X77551Y630121D01*
X77801Y630288D01*
X78093Y630371D01*
X78426Y630288D01*
X78676Y630121D01*
X78843Y629871D01*
X78926Y629538D01*
X78843Y629246D01*
X78635Y628954D01*
X78385Y628788D01*
X78093Y628746D01*
X77760Y628829D01*
X77510Y629038D01*
X77260Y629413D01*
G01X75785Y628913D02*
X75493Y629204D01*
X75243Y629371D01*
X74910Y629454D01*
X74618Y629371D01*
X74410Y629204D01*
X74243Y628954D01*
X74201Y628663D01*
X74243Y628413D01*
X74410Y628163D01*
X74660Y627954D01*
X74951Y627871D01*
X75285Y627954D01*
X75576Y628204D01*
X75743Y628579D01*
X75785Y628996D01*
X75701Y629538D01*
X75576Y629829D01*
X75368Y630121D01*
X75076Y630329D01*
X74785Y630371D01*
X74493Y630288D01*
X74285Y630079D01*
G01X70340Y614626D02*
X72840D01*
Y615667D01*
X72715Y616001D01*
X72548Y616209D01*
X72215Y616292D01*
X71882Y616209D01*
X71673Y615959D01*
X71548Y615667D01*
Y614626D01*
G01Y615667D02*
X70340Y616292D01*
G01Y618559D02*
X72840D01*
X72340Y618059D01*
G01X70340D02*
Y619059D01*
G01X70632Y620951D02*
X70423Y621242D01*
X70340Y621576D01*
X70423Y621909D01*
X70673Y622201D01*
X71048Y622409D01*
X71423Y622492D01*
X71882D01*
X72257Y622409D01*
X72590Y622201D01*
X72757Y621951D01*
X72840Y621659D01*
X72757Y621326D01*
X72590Y621076D01*
X72340Y620909D01*
X72007Y620826D01*
X71715Y620909D01*
X71423Y621117D01*
X71257Y621367D01*
X71215Y621659D01*
X71298Y621992D01*
X71507Y622242D01*
X71882Y622492D01*
G01X70715Y623842D02*
X70507Y624092D01*
X70382Y624384D01*
X70340Y624759D01*
X70423Y625134D01*
X70590Y625426D01*
X70882Y625634D01*
X71215Y625676D01*
X71548Y625592D01*
X71757Y625384D01*
X71923Y625092D01*
X71965Y624801D01*
X71923Y624509D01*
X71757Y624134D01*
X72840Y624259D01*
Y625384D01*
G01X82656Y599776D02*
Y602276D01*
X81615D01*
X81281Y602151D01*
X81073Y601984D01*
X80990Y601651D01*
X81073Y601318D01*
X81323Y601109D01*
X81615Y600984D01*
X82656D01*
G01X81615D02*
X80990Y599776D01*
G01X78723D02*
Y602276D01*
X79223Y601776D01*
G01Y599776D02*
X78223D01*
G01X75623D02*
X75331Y599818D01*
X74998Y599943D01*
X74790Y600151D01*
X74706Y600443D01*
X74790Y600734D01*
X75040Y600984D01*
X75415Y601109D01*
X75831D01*
X76081Y601193D01*
X76290Y601401D01*
X76373Y601693D01*
X76248Y601984D01*
X75956Y602193D01*
X75623Y602276D01*
X75290Y602193D01*
X74998Y601984D01*
X74873Y601693D01*
X74956Y601401D01*
X75165Y601193D01*
X75415Y601109D01*
X75831D01*
X76206Y600984D01*
X76456Y600734D01*
X76540Y600443D01*
X76456Y600151D01*
X76248Y599943D01*
X75915Y599818D01*
X75623Y599776D01*
G01X73315Y600818D02*
X73023Y601109D01*
X72773Y601276D01*
X72440Y601359D01*
X72148Y601276D01*
X71940Y601109D01*
X71773Y600859D01*
X71731Y600568D01*
X71773Y600318D01*
X71940Y600068D01*
X72190Y599859D01*
X72481Y599776D01*
X72815Y599859D01*
X73106Y600109D01*
X73273Y600484D01*
X73315Y600901D01*
X73231Y601443D01*
X73106Y601734D01*
X72898Y602026D01*
X72606Y602234D01*
X72315Y602276D01*
X72023Y602193D01*
X71815Y601984D01*
G01X134483Y588000D02*
Y590500D01*
X133442D01*
X133108Y590375D01*
X132900Y590208D01*
X132817Y589875D01*
X132900Y589542D01*
X133150Y589333D01*
X133442Y589208D01*
X134483D01*
G01X133442D02*
X132817Y588000D01*
G01X131467Y588500D02*
X131217Y588208D01*
X130883Y588042D01*
X130508Y588000D01*
X130175Y588042D01*
X129842Y588250D01*
X129633Y588500D01*
X129592Y588750D01*
X129675Y589042D01*
X129967Y589250D01*
X130258Y589333D01*
X130633D01*
G01X130258D02*
X130008Y589458D01*
X129800Y589667D01*
X129717Y589917D01*
X129800Y590167D01*
X130008Y590375D01*
X130383Y590500D01*
X130758Y590458D01*
X131133Y590292D01*
G01X128242Y590083D02*
X127992Y590333D01*
X127700Y590458D01*
X127367Y590500D01*
X126950Y590417D01*
X126658Y590208D01*
X126575Y589958D01*
X126617Y589708D01*
X126783Y589500D01*
X127617Y589083D01*
X127992Y588792D01*
X128242Y588375D01*
X128325Y588000D01*
X126575D01*
G01X124350D02*
Y590500D01*
X124850Y590000D01*
G01Y588000D02*
X123850D01*
G01X134483Y584500D02*
Y587000D01*
X133442D01*
X133108Y586875D01*
X132900Y586708D01*
X132817Y586375D01*
X132900Y586042D01*
X133150Y585833D01*
X133442Y585708D01*
X134483D01*
G01X133442D02*
X132817Y584500D01*
G01X131467Y585000D02*
X131217Y584708D01*
X130883Y584542D01*
X130508Y584500D01*
X130175Y584542D01*
X129842Y584750D01*
X129633Y585000D01*
X129592Y585250D01*
X129675Y585542D01*
X129967Y585750D01*
X130258Y585833D01*
X130633D01*
G01X130258D02*
X130008Y585958D01*
X129800Y586167D01*
X129717Y586417D01*
X129800Y586667D01*
X130008Y586875D01*
X130383Y587000D01*
X130758Y586958D01*
X131133Y586792D01*
G01X127450Y584500D02*
Y587000D01*
X127950Y586500D01*
G01Y584500D02*
X126950D01*
G01X124350D02*
X124058Y584542D01*
X123725Y584667D01*
X123517Y584875D01*
X123433Y585167D01*
X123517Y585458D01*
X123767Y585708D01*
X124142Y585833D01*
X124558D01*
X124808Y585917D01*
X125017Y586125D01*
X125100Y586417D01*
X124975Y586708D01*
X124683Y586917D01*
X124350Y587000D01*
X124017Y586917D01*
X123725Y586708D01*
X123600Y586417D01*
X123683Y586125D01*
X123892Y585917D01*
X124142Y585833D01*
X124558D01*
X124933Y585708D01*
X125183Y585458D01*
X125267Y585167D01*
X125183Y584875D01*
X124975Y584667D01*
X124642Y584542D01*
X124350Y584500D01*
G01X105604Y614355D02*
Y616855D01*
X104563D01*
X104229Y616730D01*
X104021Y616563D01*
X103938Y616230D01*
X104021Y615897D01*
X104271Y615688D01*
X104563Y615563D01*
X105604D01*
G01X104563D02*
X103938Y614355D01*
G01X102588Y614855D02*
X102338Y614563D01*
X102004Y614397D01*
X101629Y614355D01*
X101296Y614397D01*
X100963Y614605D01*
X100754Y614855D01*
X100713Y615105D01*
X100796Y615397D01*
X101088Y615605D01*
X101379Y615688D01*
X101754D01*
G01X101379D02*
X101129Y615813D01*
X100921Y616022D01*
X100838Y616272D01*
X100921Y616522D01*
X101129Y616730D01*
X101504Y616855D01*
X101879Y616813D01*
X102254Y616647D01*
G01X99488Y614855D02*
X99238Y614563D01*
X98904Y614397D01*
X98529Y614355D01*
X98196Y614397D01*
X97863Y614605D01*
X97654Y614855D01*
X97613Y615105D01*
X97696Y615397D01*
X97988Y615605D01*
X98279Y615688D01*
X98654D01*
G01X98279D02*
X98029Y615813D01*
X97821Y616022D01*
X97738Y616272D01*
X97821Y616522D01*
X98029Y616730D01*
X98404Y616855D01*
X98779Y616813D01*
X99154Y616647D01*
G01X96263Y615397D02*
X95971Y615688D01*
X95721Y615855D01*
X95388Y615938D01*
X95096Y615855D01*
X94888Y615688D01*
X94721Y615438D01*
X94679Y615147D01*
X94721Y614897D01*
X94888Y614647D01*
X95138Y614438D01*
X95429Y614355D01*
X95763Y614438D01*
X96054Y614688D01*
X96221Y615063D01*
X96263Y615480D01*
X96179Y616022D01*
X96054Y616313D01*
X95846Y616605D01*
X95554Y616813D01*
X95263Y616855D01*
X94971Y616772D01*
X94763Y616563D01*
G01X122800Y608500D02*
Y612500D01*
X130200D01*
G01X96500Y619617D02*
X99000D01*
Y620658D01*
X98875Y620992D01*
X98708Y621200D01*
X98375Y621283D01*
X98042Y621200D01*
X97833Y620950D01*
X97708Y620658D01*
Y619617D01*
G01Y620658D02*
X96500Y621283D01*
G01Y623467D02*
X97042Y623550D01*
X97500Y623675D01*
X97917Y623842D01*
X98375Y624050D01*
X99000Y624383D01*
Y622717D01*
G01X96500Y626650D02*
X96542Y626942D01*
X96667Y627275D01*
X96875Y627483D01*
X97167Y627567D01*
X97458Y627483D01*
X97708Y627233D01*
X97833Y626858D01*
Y626442D01*
X97917Y626192D01*
X98125Y625983D01*
X98417Y625900D01*
X98708Y626025D01*
X98917Y626317D01*
X99000Y626650D01*
X98917Y626983D01*
X98708Y627275D01*
X98417Y627400D01*
X98125Y627317D01*
X97917Y627108D01*
X97833Y626858D01*
Y626442D01*
X97708Y626067D01*
X97458Y625817D01*
X97167Y625733D01*
X96875Y625817D01*
X96667Y626025D01*
X96542Y626358D01*
X96500Y626650D01*
G01X98583Y628958D02*
X98833Y629208D01*
X98958Y629500D01*
X99000Y629833D01*
X98917Y630250D01*
X98708Y630542D01*
X98458Y630625D01*
X98208Y630583D01*
X98000Y630417D01*
X97583Y629583D01*
X97292Y629208D01*
X96875Y628958D01*
X96500Y628875D01*
Y630625D01*
G01X123643Y612627D02*
X119643D01*
Y620027D01*
G01X105300Y619217D02*
X107800D01*
Y620258D01*
X107675Y620592D01*
X107508Y620800D01*
X107175Y620883D01*
X106842Y620800D01*
X106633Y620550D01*
X106508Y620258D01*
Y619217D01*
G01Y620258D02*
X105300Y620883D01*
G01Y623067D02*
X105842Y623150D01*
X106300Y623275D01*
X106717Y623442D01*
X107175Y623650D01*
X107800Y623983D01*
Y622317D01*
G01X105300Y626167D02*
X105842Y626250D01*
X106300Y626375D01*
X106717Y626542D01*
X107175Y626750D01*
X107800Y627083D01*
Y625417D01*
G01X106342Y628558D02*
X106633Y628850D01*
X106800Y629100D01*
X106883Y629433D01*
X106800Y629725D01*
X106633Y629933D01*
X106383Y630100D01*
X106092Y630142D01*
X105842Y630100D01*
X105592Y629933D01*
X105383Y629683D01*
X105300Y629392D01*
X105383Y629058D01*
X105633Y628767D01*
X106008Y628600D01*
X106425Y628558D01*
X106967Y628642D01*
X107258Y628767D01*
X107550Y628975D01*
X107758Y629267D01*
X107800Y629558D01*
X107717Y629850D01*
X107508Y630058D01*
G01X131600Y619700D02*
X135600D01*
Y612300D01*
G01X134483Y581000D02*
Y583500D01*
X133442D01*
X133108Y583375D01*
X132900Y583208D01*
X132817Y582875D01*
X132900Y582542D01*
X133150Y582333D01*
X133442Y582208D01*
X134483D01*
G01X133442D02*
X132817Y581000D01*
G01X130633D02*
X130550Y581542D01*
X130425Y582000D01*
X130258Y582417D01*
X130050Y582875D01*
X129717Y583500D01*
X131383D01*
G01X126950Y581000D02*
Y583500D01*
X128492Y581708D01*
X126408D01*
G01X124350Y583500D02*
X124683Y583417D01*
X124933Y583208D01*
X125100Y582958D01*
X125225Y582625D01*
X125267Y582250D01*
X125225Y581875D01*
X125100Y581542D01*
X124933Y581292D01*
X124683Y581083D01*
X124350Y581000D01*
X124017Y581083D01*
X123767Y581292D01*
X123600Y581542D01*
X123475Y581875D01*
X123433Y582250D01*
X123475Y582625D01*
X123600Y582958D01*
X123767Y583208D01*
X124017Y583417D01*
X124350Y583500D01*
G01X145200Y622200D02*
Y618200D01*
X137800D01*
G01X120383Y632600D02*
Y635100D01*
X119342D01*
X119008Y634975D01*
X118800Y634808D01*
X118717Y634475D01*
X118800Y634142D01*
X119050Y633933D01*
X119342Y633808D01*
X120383D01*
G01X119342D02*
X118717Y632600D01*
G01X116533D02*
X116450Y633142D01*
X116325Y633600D01*
X116158Y634017D01*
X115950Y634475D01*
X115617Y635100D01*
X117283D01*
G01X113350D02*
X113683Y635017D01*
X113933Y634808D01*
X114100Y634558D01*
X114225Y634225D01*
X114267Y633850D01*
X114225Y633475D01*
X114100Y633142D01*
X113933Y632892D01*
X113683Y632683D01*
X113350Y632600D01*
X113017Y632683D01*
X112767Y632892D01*
X112600Y633142D01*
X112475Y633475D01*
X112433Y633850D01*
X112475Y634225D01*
X112600Y634558D01*
X112767Y634808D01*
X113017Y635017D01*
X113350Y635100D01*
G01X111167Y632975D02*
X110917Y632767D01*
X110625Y632642D01*
X110250Y632600D01*
X109875Y632683D01*
X109583Y632850D01*
X109375Y633142D01*
X109333Y633475D01*
X109417Y633808D01*
X109625Y634017D01*
X109917Y634183D01*
X110208Y634225D01*
X110500Y634183D01*
X110875Y634017D01*
X110750Y635100D01*
X109625D01*
G01X124400Y628800D02*
Y632800D01*
X131800D01*
G01X124400Y637000D02*
Y641000D01*
X131800D01*
G01X120883Y628500D02*
Y631000D01*
X119842D01*
X119508Y630875D01*
X119300Y630708D01*
X119217Y630375D01*
X119300Y630042D01*
X119550Y629833D01*
X119842Y629708D01*
X120883D01*
G01X119842D02*
X119217Y628500D01*
G01X117742Y629542D02*
X117450Y629833D01*
X117200Y630000D01*
X116867Y630083D01*
X116575Y630000D01*
X116367Y629833D01*
X116200Y629583D01*
X116158Y629292D01*
X116200Y629042D01*
X116367Y628792D01*
X116617Y628583D01*
X116908Y628500D01*
X117242Y628583D01*
X117533Y628833D01*
X117700Y629208D01*
X117742Y629625D01*
X117658Y630167D01*
X117533Y630458D01*
X117325Y630750D01*
X117033Y630958D01*
X116742Y631000D01*
X116450Y630917D01*
X116242Y630708D01*
G01X114558Y628792D02*
X114267Y628583D01*
X113933Y628500D01*
X113600Y628583D01*
X113308Y628833D01*
X113100Y629208D01*
X113017Y629583D01*
Y630042D01*
X113100Y630417D01*
X113308Y630750D01*
X113558Y630917D01*
X113850Y631000D01*
X114183Y630917D01*
X114433Y630750D01*
X114600Y630500D01*
X114683Y630167D01*
X114600Y629875D01*
X114392Y629583D01*
X114142Y629417D01*
X113850Y629375D01*
X113517Y629458D01*
X113267Y629667D01*
X113017Y630042D01*
G01X111458Y628792D02*
X111167Y628583D01*
X110833Y628500D01*
X110500Y628583D01*
X110208Y628833D01*
X110000Y629208D01*
X109917Y629583D01*
Y630042D01*
X110000Y630417D01*
X110208Y630750D01*
X110458Y630917D01*
X110750Y631000D01*
X111083Y630917D01*
X111333Y630750D01*
X111500Y630500D01*
X111583Y630167D01*
X111500Y629875D01*
X111292Y629583D01*
X111042Y629417D01*
X110750Y629375D01*
X110417Y629458D01*
X110167Y629667D01*
X109917Y630042D01*
G01X131600Y628300D02*
Y624300D01*
X124200D01*
G01X120083Y636800D02*
Y639300D01*
X119042D01*
X118708Y639175D01*
X118500Y639008D01*
X118417Y638675D01*
X118500Y638342D01*
X118750Y638133D01*
X119042Y638008D01*
X120083D01*
G01X119042D02*
X118417Y636800D01*
G01X116942Y637842D02*
X116650Y638133D01*
X116400Y638300D01*
X116067Y638383D01*
X115775Y638300D01*
X115567Y638133D01*
X115400Y637883D01*
X115358Y637592D01*
X115400Y637342D01*
X115567Y637092D01*
X115817Y636883D01*
X116108Y636800D01*
X116442Y636883D01*
X116733Y637133D01*
X116900Y637508D01*
X116942Y637925D01*
X116858Y638467D01*
X116733Y638758D01*
X116525Y639050D01*
X116233Y639258D01*
X115942Y639300D01*
X115650Y639217D01*
X115442Y639008D01*
G01X113758Y637092D02*
X113467Y636883D01*
X113133Y636800D01*
X112800Y636883D01*
X112508Y637133D01*
X112300Y637508D01*
X112217Y637883D01*
Y638342D01*
X112300Y638717D01*
X112508Y639050D01*
X112758Y639217D01*
X113050Y639300D01*
X113383Y639217D01*
X113633Y639050D01*
X113800Y638800D01*
X113883Y638467D01*
X113800Y638175D01*
X113592Y637883D01*
X113342Y637717D01*
X113050Y637675D01*
X112717Y637758D01*
X112467Y637967D01*
X112217Y638342D01*
G01X109950Y636800D02*
X109658Y636842D01*
X109325Y636967D01*
X109117Y637175D01*
X109033Y637467D01*
X109117Y637758D01*
X109367Y638008D01*
X109742Y638133D01*
X110158D01*
X110408Y638217D01*
X110617Y638425D01*
X110700Y638717D01*
X110575Y639008D01*
X110283Y639217D01*
X109950Y639300D01*
X109617Y639217D01*
X109325Y639008D01*
X109200Y638717D01*
X109283Y638425D01*
X109492Y638217D01*
X109742Y638133D01*
X110158D01*
X110533Y638008D01*
X110783Y637758D01*
X110867Y637467D01*
X110783Y637175D01*
X110575Y636967D01*
X110242Y636842D01*
X109950Y636800D01*
G01X124400Y632900D02*
Y636900D01*
X131800D01*
G01X145950Y609000D02*
Y606500D01*
G01X146908Y609000D02*
X144992D01*
G01X143683Y606500D02*
Y609000D01*
X142683D01*
X142350Y608875D01*
X142100Y608583D01*
X142017Y608250D01*
X142100Y607917D01*
X142308Y607667D01*
X142683Y607542D01*
X143683D01*
G01X140542D02*
X140250Y607833D01*
X140000Y608000D01*
X139667Y608083D01*
X139375Y608000D01*
X139167Y607833D01*
X139000Y607583D01*
X138958Y607292D01*
X139000Y607042D01*
X139167Y606792D01*
X139417Y606583D01*
X139708Y606500D01*
X140042Y606583D01*
X140333Y606833D01*
X140500Y607208D01*
X140542Y607625D01*
X140458Y608167D01*
X140333Y608458D01*
X140125Y608750D01*
X139833Y608958D01*
X139542Y609000D01*
X139250Y608917D01*
X139042Y608708D01*
G01X136150Y606500D02*
Y609000D01*
X137692Y607208D01*
X135608D01*
G01X104959Y592717D02*
X105084Y592467D01*
X105167Y592175D01*
Y591842D01*
X105042Y591467D01*
X104834Y591175D01*
X104584Y590967D01*
X104167Y590800D01*
X103792Y590758D01*
X103417Y590842D01*
X103167Y590967D01*
X102917Y591217D01*
X102750Y591508D01*
X102667Y591800D01*
Y592092D01*
X102750Y592383D01*
X102875Y592633D01*
X103042Y592842D01*
G01X102959Y594192D02*
X102750Y594483D01*
X102667Y594817D01*
X102750Y595150D01*
X103000Y595442D01*
X103375Y595650D01*
X103750Y595733D01*
X104209D01*
X104584Y595650D01*
X104917Y595442D01*
X105084Y595192D01*
X105167Y594900D01*
X105084Y594567D01*
X104917Y594317D01*
X104667Y594150D01*
X104334Y594067D01*
X104042Y594150D01*
X103750Y594358D01*
X103584Y594608D01*
X103542Y594900D01*
X103625Y595233D01*
X103834Y595483D01*
X104209Y595733D01*
G01X104750Y597208D02*
X105000Y597458D01*
X105125Y597750D01*
X105167Y598083D01*
X105084Y598500D01*
X104875Y598792D01*
X104625Y598875D01*
X104375Y598833D01*
X104167Y598667D01*
X103750Y597833D01*
X103459Y597458D01*
X103042Y597208D01*
X102667Y597125D01*
Y598875D01*
G01X132459Y573317D02*
X132584Y573067D01*
X132667Y572775D01*
Y572442D01*
X132542Y572067D01*
X132334Y571775D01*
X132084Y571567D01*
X131667Y571400D01*
X131292Y571358D01*
X130917Y571442D01*
X130667Y571567D01*
X130417Y571817D01*
X130250Y572108D01*
X130167Y572400D01*
Y572692D01*
X130250Y572983D01*
X130375Y573233D01*
X130542Y573442D01*
G01X131209Y574708D02*
X131500Y575000D01*
X131667Y575250D01*
X131750Y575583D01*
X131667Y575875D01*
X131500Y576083D01*
X131250Y576250D01*
X130959Y576292D01*
X130709Y576250D01*
X130459Y576083D01*
X130250Y575833D01*
X130167Y575542D01*
X130250Y575208D01*
X130500Y574917D01*
X130875Y574750D01*
X131292Y574708D01*
X131834Y574792D01*
X132125Y574917D01*
X132417Y575125D01*
X132625Y575417D01*
X132667Y575708D01*
X132584Y576000D01*
X132375Y576208D01*
G01X132667Y578600D02*
X132584Y578267D01*
X132375Y578017D01*
X132125Y577850D01*
X131792Y577725D01*
X131417Y577683D01*
X131042Y577725D01*
X130709Y577850D01*
X130459Y578017D01*
X130250Y578267D01*
X130167Y578600D01*
X130250Y578933D01*
X130459Y579183D01*
X130709Y579350D01*
X131042Y579475D01*
X131417Y579517D01*
X131792Y579475D01*
X132125Y579350D01*
X132375Y579183D01*
X132584Y578933D01*
X132667Y578600D01*
G01X136459Y573317D02*
X136584Y573067D01*
X136667Y572775D01*
Y572442D01*
X136542Y572067D01*
X136334Y571775D01*
X136084Y571567D01*
X135667Y571400D01*
X135292Y571358D01*
X134917Y571442D01*
X134667Y571567D01*
X134417Y571817D01*
X134250Y572108D01*
X134167Y572400D01*
Y572692D01*
X134250Y572983D01*
X134375Y573233D01*
X134542Y573442D01*
G01Y574583D02*
X134334Y574833D01*
X134209Y575125D01*
X134167Y575500D01*
X134250Y575875D01*
X134417Y576167D01*
X134709Y576375D01*
X135042Y576417D01*
X135375Y576333D01*
X135584Y576125D01*
X135750Y575833D01*
X135792Y575542D01*
X135750Y575250D01*
X135584Y574875D01*
X136667Y575000D01*
Y576125D01*
G01X134459Y577892D02*
X134250Y578183D01*
X134167Y578517D01*
X134250Y578850D01*
X134500Y579142D01*
X134875Y579350D01*
X135250Y579433D01*
X135709D01*
X136084Y579350D01*
X136417Y579142D01*
X136584Y578892D01*
X136667Y578600D01*
X136584Y578267D01*
X136417Y578017D01*
X136167Y577850D01*
X135834Y577767D01*
X135542Y577850D01*
X135250Y578058D01*
X135084Y578308D01*
X135042Y578600D01*
X135125Y578933D01*
X135334Y579183D01*
X135709Y579433D01*
G01X140459Y573317D02*
X140584Y573067D01*
X140667Y572775D01*
Y572442D01*
X140542Y572067D01*
X140334Y571775D01*
X140084Y571567D01*
X139667Y571400D01*
X139292Y571358D01*
X138917Y571442D01*
X138667Y571567D01*
X138417Y571817D01*
X138250Y572108D01*
X138167Y572400D01*
Y572692D01*
X138250Y572983D01*
X138375Y573233D01*
X138542Y573442D01*
G01Y574583D02*
X138334Y574833D01*
X138209Y575125D01*
X138167Y575500D01*
X138250Y575875D01*
X138417Y576167D01*
X138709Y576375D01*
X139042Y576417D01*
X139375Y576333D01*
X139584Y576125D01*
X139750Y575833D01*
X139792Y575542D01*
X139750Y575250D01*
X139584Y574875D01*
X140667Y575000D01*
Y576125D01*
G01X138167Y578600D02*
X138209Y578892D01*
X138334Y579225D01*
X138542Y579433D01*
X138834Y579517D01*
X139125Y579433D01*
X139375Y579183D01*
X139500Y578808D01*
Y578392D01*
X139584Y578142D01*
X139792Y577933D01*
X140084Y577850D01*
X140375Y577975D01*
X140584Y578267D01*
X140667Y578600D01*
X140584Y578933D01*
X140375Y579225D01*
X140084Y579350D01*
X139792Y579267D01*
X139584Y579058D01*
X139500Y578808D01*
Y578392D01*
X139375Y578017D01*
X139125Y577767D01*
X138834Y577683D01*
X138542Y577767D01*
X138334Y577975D01*
X138209Y578308D01*
X138167Y578600D01*
G01X116792Y592817D02*
X116917Y592567D01*
X117000Y592275D01*
Y591942D01*
X116875Y591567D01*
X116667Y591275D01*
X116417Y591067D01*
X116000Y590900D01*
X115625Y590858D01*
X115250Y590942D01*
X115000Y591067D01*
X114750Y591317D01*
X114583Y591608D01*
X114500Y591900D01*
Y592192D01*
X114583Y592483D01*
X114708Y592733D01*
X114875Y592942D01*
G01Y594083D02*
X114667Y594333D01*
X114542Y594625D01*
X114500Y595000D01*
X114583Y595375D01*
X114750Y595667D01*
X115042Y595875D01*
X115375Y595917D01*
X115708Y595833D01*
X115917Y595625D01*
X116083Y595333D01*
X116125Y595042D01*
X116083Y594750D01*
X115917Y594375D01*
X117000Y594500D01*
Y595625D01*
G01X114500Y598600D02*
X117000D01*
X115208Y597058D01*
Y599142D01*
G01X101167Y591017D02*
X98667D01*
Y592683D01*
G01X99167Y594033D02*
X98875Y594283D01*
X98709Y594617D01*
X98667Y594992D01*
X98709Y595325D01*
X98917Y595658D01*
X99167Y595867D01*
X99417Y595908D01*
X99709Y595825D01*
X99917Y595533D01*
X100000Y595242D01*
Y594867D01*
G01Y595242D02*
X100125Y595492D01*
X100334Y595700D01*
X100584Y595783D01*
X100834Y595700D01*
X101042Y595492D01*
X101167Y595117D01*
X101125Y594742D01*
X100959Y594367D01*
G01X126100Y605300D02*
X119100D01*
Y591900D01*
X126100D01*
Y605300D01*
G01X100733Y697459D02*
X100983Y697584D01*
X101275Y697667D01*
X101608D01*
X101983Y697542D01*
X102275Y697334D01*
X102483Y697084D01*
X102650Y696667D01*
X102692Y696292D01*
X102608Y695917D01*
X102483Y695667D01*
X102233Y695417D01*
X101942Y695250D01*
X101650Y695167D01*
X101358D01*
X101067Y695250D01*
X100817Y695375D01*
X100608Y695542D01*
G01X98550Y695167D02*
Y697667D01*
X99050Y697167D01*
G01Y695167D02*
X98050D01*
G01X95533D02*
X95450Y695709D01*
X95325Y696167D01*
X95158Y696584D01*
X94950Y697042D01*
X94617Y697667D01*
X96283D01*
G01X93058Y695459D02*
X92767Y695250D01*
X92433Y695167D01*
X92100Y695250D01*
X91808Y695500D01*
X91600Y695875D01*
X91517Y696250D01*
Y696709D01*
X91600Y697084D01*
X91808Y697417D01*
X92058Y697584D01*
X92350Y697667D01*
X92683Y697584D01*
X92933Y697417D01*
X93100Y697167D01*
X93183Y696834D01*
X93100Y696542D01*
X92892Y696250D01*
X92642Y696084D01*
X92350Y696042D01*
X92017Y696125D01*
X91767Y696334D01*
X91517Y696709D01*
G01X69934Y642326D02*
X72434D01*
Y643367D01*
X72309Y643701D01*
X72142Y643909D01*
X71809Y643992D01*
X71476Y643909D01*
X71267Y643659D01*
X71142Y643367D01*
Y642326D01*
G01Y643367D02*
X69934Y643992D01*
G01X70434Y645342D02*
X70142Y645592D01*
X69976Y645926D01*
X69934Y646301D01*
X69976Y646634D01*
X70184Y646967D01*
X70434Y647176D01*
X70684Y647217D01*
X70976Y647134D01*
X71184Y646842D01*
X71267Y646551D01*
Y646176D01*
G01Y646551D02*
X71392Y646801D01*
X71601Y647009D01*
X71851Y647092D01*
X72101Y647009D01*
X72309Y646801D01*
X72434Y646426D01*
X72392Y646051D01*
X72226Y645676D01*
G01X69934Y649359D02*
X69976Y649651D01*
X70101Y649984D01*
X70309Y650192D01*
X70601Y650276D01*
X70892Y650192D01*
X71142Y649942D01*
X71267Y649567D01*
Y649151D01*
X71351Y648901D01*
X71559Y648692D01*
X71851Y648609D01*
X72142Y648734D01*
X72351Y649026D01*
X72434Y649359D01*
X72351Y649692D01*
X72142Y649984D01*
X71851Y650109D01*
X71559Y650026D01*
X71351Y649817D01*
X71267Y649567D01*
Y649151D01*
X71142Y648776D01*
X70892Y648526D01*
X70601Y648442D01*
X70309Y648526D01*
X70101Y648734D01*
X69976Y649067D01*
X69934Y649359D01*
G01X70226Y651751D02*
X70017Y652042D01*
X69934Y652376D01*
X70017Y652709D01*
X70267Y653001D01*
X70642Y653209D01*
X71017Y653292D01*
X71476D01*
X71851Y653209D01*
X72184Y653001D01*
X72351Y652751D01*
X72434Y652459D01*
X72351Y652126D01*
X72184Y651876D01*
X71934Y651709D01*
X71601Y651626D01*
X71309Y651709D01*
X71017Y651917D01*
X70851Y652167D01*
X70809Y652459D01*
X70892Y652792D01*
X71101Y653042D01*
X71476Y653292D01*
G01X143983Y638500D02*
Y641000D01*
X142942D01*
X142608Y640875D01*
X142400Y640708D01*
X142317Y640375D01*
X142400Y640042D01*
X142650Y639833D01*
X142942Y639708D01*
X143983D01*
G01X142942D02*
X142317Y638500D01*
G01X140133D02*
X140050Y639042D01*
X139925Y639500D01*
X139758Y639917D01*
X139550Y640375D01*
X139217Y641000D01*
X140883D01*
G01X136950D02*
X137283Y640917D01*
X137533Y640708D01*
X137700Y640458D01*
X137825Y640125D01*
X137867Y639750D01*
X137825Y639375D01*
X137700Y639042D01*
X137533Y638792D01*
X137283Y638583D01*
X136950Y638500D01*
X136617Y638583D01*
X136367Y638792D01*
X136200Y639042D01*
X136075Y639375D01*
X136033Y639750D01*
X136075Y640125D01*
X136200Y640458D01*
X136367Y640708D01*
X136617Y640917D01*
X136950Y641000D01*
G01X134642Y639542D02*
X134350Y639833D01*
X134100Y640000D01*
X133767Y640083D01*
X133475Y640000D01*
X133267Y639833D01*
X133100Y639583D01*
X133058Y639292D01*
X133100Y639042D01*
X133267Y638792D01*
X133517Y638583D01*
X133808Y638500D01*
X134142Y638583D01*
X134433Y638833D01*
X134600Y639208D01*
X134642Y639625D01*
X134558Y640167D01*
X134433Y640458D01*
X134225Y640750D01*
X133933Y640958D01*
X133642Y641000D01*
X133350Y640917D01*
X133142Y640708D01*
G01X119783Y640400D02*
Y642900D01*
X118742D01*
X118408Y642775D01*
X118200Y642608D01*
X118117Y642275D01*
X118200Y641942D01*
X118450Y641733D01*
X118742Y641608D01*
X119783D01*
G01X118742D02*
X118117Y640400D01*
G01X115933D02*
X115850Y640942D01*
X115725Y641400D01*
X115558Y641817D01*
X115350Y642275D01*
X115017Y642900D01*
X116683D01*
G01X112750D02*
X113083Y642817D01*
X113333Y642608D01*
X113500Y642358D01*
X113625Y642025D01*
X113667Y641650D01*
X113625Y641275D01*
X113500Y640942D01*
X113333Y640692D01*
X113083Y640483D01*
X112750Y640400D01*
X112417Y640483D01*
X112167Y640692D01*
X112000Y640942D01*
X111875Y641275D01*
X111833Y641650D01*
X111875Y642025D01*
X112000Y642358D01*
X112167Y642608D01*
X112417Y642817D01*
X112750Y642900D01*
G01X110567Y640900D02*
X110317Y640608D01*
X109983Y640442D01*
X109608Y640400D01*
X109275Y640442D01*
X108942Y640650D01*
X108733Y640900D01*
X108692Y641150D01*
X108775Y641442D01*
X109067Y641650D01*
X109358Y641733D01*
X109733D01*
G01X109358D02*
X109108Y641858D01*
X108900Y642067D01*
X108817Y642317D01*
X108900Y642567D01*
X109108Y642775D01*
X109483Y642900D01*
X109858Y642858D01*
X110233Y642692D01*
G01X104983Y716167D02*
Y718667D01*
X103942D01*
X103608Y718542D01*
X103400Y718375D01*
X103317Y718042D01*
X103400Y717709D01*
X103650Y717500D01*
X103942Y717375D01*
X104983D01*
G01X103942D02*
X103317Y716167D01*
G01X100550D02*
Y718667D01*
X102092Y716875D01*
X100008D01*
G01X97950Y716167D02*
X97658Y716209D01*
X97325Y716334D01*
X97117Y716542D01*
X97033Y716834D01*
X97117Y717125D01*
X97367Y717375D01*
X97742Y717500D01*
X98158D01*
X98408Y717584D01*
X98617Y717792D01*
X98700Y718084D01*
X98575Y718375D01*
X98283Y718584D01*
X97950Y718667D01*
X97617Y718584D01*
X97325Y718375D01*
X97200Y718084D01*
X97283Y717792D01*
X97492Y717584D01*
X97742Y717500D01*
X98158D01*
X98533Y717375D01*
X98783Y717125D01*
X98867Y716834D01*
X98783Y716542D01*
X98575Y716334D01*
X98242Y716209D01*
X97950Y716167D01*
G01X95767Y716667D02*
X95517Y716375D01*
X95183Y716209D01*
X94808Y716167D01*
X94475Y716209D01*
X94142Y716417D01*
X93933Y716667D01*
X93892Y716917D01*
X93975Y717209D01*
X94267Y717417D01*
X94558Y717500D01*
X94933D01*
G01X94558D02*
X94308Y717625D01*
X94100Y717834D01*
X94017Y718084D01*
X94100Y718334D01*
X94308Y718542D01*
X94683Y718667D01*
X95058Y718625D01*
X95433Y718459D01*
G01X202300Y451117D02*
X204800D01*
Y452158D01*
X204675Y452492D01*
X204508Y452700D01*
X204175Y452783D01*
X203842Y452700D01*
X203633Y452450D01*
X203508Y452158D01*
Y451117D01*
G01Y452158D02*
X202300Y452783D01*
G01Y455550D02*
X204800D01*
X203008Y454008D01*
Y456092D01*
G01X204800Y458150D02*
X204717Y457817D01*
X204508Y457567D01*
X204258Y457400D01*
X203925Y457275D01*
X203550Y457233D01*
X203175Y457275D01*
X202842Y457400D01*
X202592Y457567D01*
X202383Y457817D01*
X202300Y458150D01*
X202383Y458483D01*
X202592Y458733D01*
X202842Y458900D01*
X203175Y459025D01*
X203550Y459067D01*
X203925Y459025D01*
X204258Y458900D01*
X204508Y458733D01*
X204717Y458483D01*
X204800Y458150D01*
G01X202800Y460333D02*
X202508Y460583D01*
X202342Y460917D01*
X202300Y461292D01*
X202342Y461625D01*
X202550Y461958D01*
X202800Y462167D01*
X203050Y462208D01*
X203342Y462125D01*
X203550Y461833D01*
X203633Y461542D01*
Y461167D01*
G01Y461542D02*
X203758Y461792D01*
X203967Y462000D01*
X204217Y462083D01*
X204467Y462000D01*
X204675Y461792D01*
X204800Y461417D01*
X204758Y461042D01*
X204592Y460667D01*
G01X202800Y492500D02*
X206800D01*
Y485100D01*
G01X199683Y457500D02*
Y460000D01*
X198642D01*
X198308Y459875D01*
X198100Y459708D01*
X198017Y459375D01*
X198100Y459042D01*
X198350Y458833D01*
X198642Y458708D01*
X199683D01*
G01X198642D02*
X198017Y457500D01*
G01X195250D02*
Y460000D01*
X196792Y458208D01*
X194708D01*
G01X192650Y460000D02*
X192983Y459917D01*
X193233Y459708D01*
X193400Y459458D01*
X193525Y459125D01*
X193567Y458750D01*
X193525Y458375D01*
X193400Y458042D01*
X193233Y457792D01*
X192983Y457583D01*
X192650Y457500D01*
X192317Y457583D01*
X192067Y457792D01*
X191900Y458042D01*
X191775Y458375D01*
X191733Y458750D01*
X191775Y459125D01*
X191900Y459458D01*
X192067Y459708D01*
X192317Y459917D01*
X192650Y460000D01*
G01X190342Y458542D02*
X190050Y458833D01*
X189800Y459000D01*
X189467Y459083D01*
X189175Y459000D01*
X188967Y458833D01*
X188800Y458583D01*
X188758Y458292D01*
X188800Y458042D01*
X188967Y457792D01*
X189217Y457583D01*
X189508Y457500D01*
X189842Y457583D01*
X190133Y457833D01*
X190300Y458208D01*
X190342Y458625D01*
X190258Y459167D01*
X190133Y459458D01*
X189925Y459750D01*
X189633Y459958D01*
X189342Y460000D01*
X189050Y459917D01*
X188842Y459708D01*
G01X194800Y487500D02*
Y491500D01*
X202200D01*
G01X141826Y440710D02*
X144326D01*
Y441751D01*
X144201Y442085D01*
X144034Y442293D01*
X143701Y442376D01*
X143368Y442293D01*
X143159Y442043D01*
X143034Y441751D01*
Y440710D01*
G01Y441751D02*
X141826Y442376D01*
G01X142326Y443726D02*
X142034Y443976D01*
X141868Y444310D01*
X141826Y444685D01*
X141868Y445018D01*
X142076Y445351D01*
X142326Y445560D01*
X142576Y445601D01*
X142868Y445518D01*
X143076Y445226D01*
X143159Y444935D01*
Y444560D01*
G01Y444935D02*
X143284Y445185D01*
X143493Y445393D01*
X143743Y445476D01*
X143993Y445393D01*
X144201Y445185D01*
X144326Y444810D01*
X144284Y444435D01*
X144118Y444060D01*
G01X142868Y446951D02*
X143159Y447243D01*
X143326Y447493D01*
X143409Y447826D01*
X143326Y448118D01*
X143159Y448326D01*
X142909Y448493D01*
X142618Y448535D01*
X142368Y448493D01*
X142118Y448326D01*
X141909Y448076D01*
X141826Y447785D01*
X141909Y447451D01*
X142159Y447160D01*
X142534Y446993D01*
X142951Y446951D01*
X143493Y447035D01*
X143784Y447160D01*
X144076Y447368D01*
X144284Y447660D01*
X144326Y447951D01*
X144243Y448243D01*
X144034Y448451D01*
G01X141826Y451343D02*
X144326D01*
X142534Y449801D01*
Y451885D01*
G01X164761Y497720D02*
X168761D01*
Y490320D01*
G01X164700Y490300D02*
X160700D01*
Y497700D01*
G01X150000Y470100D02*
X146000D01*
Y477500D01*
G01X145700Y470100D02*
X141700D01*
Y477500D01*
G01X143416Y453835D02*
X145916D01*
Y454876D01*
X145791Y455210D01*
X145624Y455418D01*
X145291Y455501D01*
X144958Y455418D01*
X144749Y455168D01*
X144624Y454876D01*
Y453835D01*
G01Y454876D02*
X143416Y455501D01*
G01X143916Y456851D02*
X143624Y457101D01*
X143458Y457435D01*
X143416Y457810D01*
X143458Y458143D01*
X143666Y458476D01*
X143916Y458685D01*
X144166Y458726D01*
X144458Y458643D01*
X144666Y458351D01*
X144749Y458060D01*
Y457685D01*
G01Y458060D02*
X144874Y458310D01*
X145083Y458518D01*
X145333Y458601D01*
X145583Y458518D01*
X145791Y458310D01*
X145916Y457935D01*
X145874Y457560D01*
X145708Y457185D01*
G01X143416Y460785D02*
X143958Y460868D01*
X144416Y460993D01*
X144833Y461160D01*
X145291Y461368D01*
X145916Y461701D01*
Y460035D01*
G01X143416Y463968D02*
X145916D01*
X145416Y463468D01*
G01X143416D02*
Y464468D01*
G01X147516Y453835D02*
X150016D01*
Y454876D01*
X149891Y455210D01*
X149724Y455418D01*
X149391Y455501D01*
X149058Y455418D01*
X148849Y455168D01*
X148724Y454876D01*
Y453835D01*
G01Y454876D02*
X147516Y455501D01*
G01X149599Y456976D02*
X149849Y457226D01*
X149974Y457518D01*
X150016Y457851D01*
X149933Y458268D01*
X149724Y458560D01*
X149474Y458643D01*
X149224Y458601D01*
X149016Y458435D01*
X148599Y457601D01*
X148308Y457226D01*
X147891Y456976D01*
X147516Y456893D01*
Y458643D01*
G01X147808Y460160D02*
X147599Y460451D01*
X147516Y460785D01*
X147599Y461118D01*
X147849Y461410D01*
X148224Y461618D01*
X148599Y461701D01*
X149058D01*
X149433Y461618D01*
X149766Y461410D01*
X149933Y461160D01*
X150016Y460868D01*
X149933Y460535D01*
X149766Y460285D01*
X149516Y460118D01*
X149183Y460035D01*
X148891Y460118D01*
X148599Y460326D01*
X148433Y460576D01*
X148391Y460868D01*
X148474Y461201D01*
X148683Y461451D01*
X149058Y461701D01*
G01X149599Y463176D02*
X149849Y463426D01*
X149974Y463718D01*
X150016Y464051D01*
X149933Y464468D01*
X149724Y464760D01*
X149474Y464843D01*
X149224Y464801D01*
X149016Y464635D01*
X148599Y463801D01*
X148308Y463426D01*
X147891Y463176D01*
X147516Y463093D01*
Y464843D01*
G01X180983Y488000D02*
Y490500D01*
X179942D01*
X179608Y490375D01*
X179400Y490208D01*
X179317Y489875D01*
X179400Y489542D01*
X179650Y489333D01*
X179942Y489208D01*
X180983D01*
G01X179942D02*
X179317Y488000D01*
G01X177050D02*
Y490500D01*
X177550Y490000D01*
G01Y488000D02*
X176550D01*
G01X174867Y488375D02*
X174617Y488167D01*
X174325Y488042D01*
X173950Y488000D01*
X173575Y488083D01*
X173283Y488250D01*
X173075Y488542D01*
X173033Y488875D01*
X173117Y489208D01*
X173325Y489417D01*
X173617Y489583D01*
X173908Y489625D01*
X174200Y489583D01*
X174575Y489417D01*
X174450Y490500D01*
X173325D01*
G01X171642Y489042D02*
X171350Y489333D01*
X171100Y489500D01*
X170767Y489583D01*
X170475Y489500D01*
X170267Y489333D01*
X170100Y489083D01*
X170058Y488792D01*
X170100Y488542D01*
X170267Y488292D01*
X170517Y488083D01*
X170808Y488000D01*
X171142Y488083D01*
X171433Y488333D01*
X171600Y488708D01*
X171642Y489125D01*
X171558Y489667D01*
X171433Y489958D01*
X171225Y490250D01*
X170933Y490458D01*
X170642Y490500D01*
X170350Y490417D01*
X170142Y490208D01*
G01X190200Y491000D02*
Y487000D01*
X182800D01*
G01X154589Y484081D02*
X150589D01*
Y491481D01*
G01X194300Y488100D02*
X190300D01*
Y495500D01*
G01X210165Y488408D02*
X214165D01*
Y481008D01*
G01X200082Y453379D02*
Y455879D01*
X199041D01*
X198707Y455754D01*
X198499Y455587D01*
X198416Y455254D01*
X198499Y454921D01*
X198749Y454712D01*
X199041Y454587D01*
X200082D01*
G01X199041D02*
X198416Y453379D01*
G01X197066Y453879D02*
X196816Y453587D01*
X196482Y453421D01*
X196107Y453379D01*
X195774Y453421D01*
X195441Y453629D01*
X195232Y453879D01*
X195191Y454129D01*
X195274Y454421D01*
X195566Y454629D01*
X195857Y454712D01*
X196232D01*
G01X195857D02*
X195607Y454837D01*
X195399Y455046D01*
X195316Y455296D01*
X195399Y455546D01*
X195607Y455754D01*
X195982Y455879D01*
X196357Y455837D01*
X196732Y455671D01*
G01X192549Y453379D02*
Y455879D01*
X194091Y454087D01*
X192007D01*
G01X189949Y453379D02*
Y455879D01*
X190449Y455379D01*
G01Y453379D02*
X189449D01*
G01X204800Y485000D02*
Y481000D01*
X197400D01*
G01X208767Y452317D02*
X211267D01*
Y453358D01*
X211142Y453692D01*
X210975Y453900D01*
X210642Y453983D01*
X210309Y453900D01*
X210100Y453650D01*
X209975Y453358D01*
Y452317D01*
G01Y453358D02*
X208767Y453983D01*
G01X210850Y455458D02*
X211100Y455708D01*
X211225Y456000D01*
X211267Y456333D01*
X211184Y456750D01*
X210975Y457042D01*
X210725Y457125D01*
X210475Y457083D01*
X210267Y456917D01*
X209850Y456083D01*
X209559Y455708D01*
X209142Y455458D01*
X208767Y455375D01*
Y457125D01*
G01Y459350D02*
X208809Y459642D01*
X208934Y459975D01*
X209142Y460183D01*
X209434Y460267D01*
X209725Y460183D01*
X209975Y459933D01*
X210100Y459558D01*
Y459142D01*
X210184Y458892D01*
X210392Y458683D01*
X210684Y458600D01*
X210975Y458725D01*
X211184Y459017D01*
X211267Y459350D01*
X211184Y459683D01*
X210975Y459975D01*
X210684Y460100D01*
X210392Y460017D01*
X210184Y459808D01*
X210100Y459558D01*
Y459142D01*
X209975Y458767D01*
X209725Y458517D01*
X209434Y458433D01*
X209142Y458517D01*
X208934Y458725D01*
X208809Y459058D01*
X208767Y459350D01*
G01X210850Y461658D02*
X211100Y461908D01*
X211225Y462200D01*
X211267Y462533D01*
X211184Y462950D01*
X210975Y463242D01*
X210725Y463325D01*
X210475Y463283D01*
X210267Y463117D01*
X209850Y462283D01*
X209559Y461908D01*
X209142Y461658D01*
X208767Y461575D01*
Y463325D01*
G01X214118Y465593D02*
X210118D01*
Y472993D01*
G01X175360Y457975D02*
Y460475D01*
X174319D01*
X173985Y460350D01*
X173777Y460183D01*
X173694Y459850D01*
X173777Y459517D01*
X174027Y459308D01*
X174319Y459183D01*
X175360D01*
G01X174319D02*
X173694Y457975D01*
G01X172344Y458475D02*
X172094Y458183D01*
X171760Y458017D01*
X171385Y457975D01*
X171052Y458017D01*
X170719Y458225D01*
X170510Y458475D01*
X170469Y458725D01*
X170552Y459017D01*
X170844Y459225D01*
X171135Y459308D01*
X171510D01*
G01X171135D02*
X170885Y459433D01*
X170677Y459642D01*
X170594Y459892D01*
X170677Y460142D01*
X170885Y460350D01*
X171260Y460475D01*
X171635Y460433D01*
X172010Y460267D01*
G01X167827Y457975D02*
Y460475D01*
X169369Y458683D01*
X167285D01*
G01X166019Y460058D02*
X165769Y460308D01*
X165477Y460433D01*
X165144Y460475D01*
X164727Y460392D01*
X164435Y460183D01*
X164352Y459933D01*
X164394Y459683D01*
X164560Y459475D01*
X165394Y459058D01*
X165769Y458767D01*
X166019Y458350D01*
X166102Y457975D01*
X164352D01*
G01X173501Y471168D02*
Y467168D01*
X166101D01*
G01X175360Y462075D02*
Y464575D01*
X174319D01*
X173985Y464450D01*
X173777Y464283D01*
X173694Y463950D01*
X173777Y463617D01*
X174027Y463408D01*
X174319Y463283D01*
X175360D01*
G01X174319D02*
X173694Y462075D01*
G01X172344Y462575D02*
X172094Y462283D01*
X171760Y462117D01*
X171385Y462075D01*
X171052Y462117D01*
X170719Y462325D01*
X170510Y462575D01*
X170469Y462825D01*
X170552Y463117D01*
X170844Y463325D01*
X171135Y463408D01*
X171510D01*
G01X171135D02*
X170885Y463533D01*
X170677Y463742D01*
X170594Y463992D01*
X170677Y464242D01*
X170885Y464450D01*
X171260Y464575D01*
X171635Y464533D01*
X172010Y464367D01*
G01X167827Y462075D02*
Y464575D01*
X169369Y462783D01*
X167285D01*
G01X164727Y462075D02*
Y464575D01*
X166269Y462783D01*
X164185D01*
G01X173501Y475268D02*
Y471268D01*
X166101D01*
G01X148770Y441320D02*
X146270D01*
G01X148770Y440362D02*
Y442278D01*
G01X146270Y443587D02*
X148770D01*
Y444587D01*
X148645Y444920D01*
X148353Y445170D01*
X148020Y445253D01*
X147687Y445170D01*
X147437Y444962D01*
X147312Y444587D01*
Y443587D01*
G01X146270Y447520D02*
X146312Y447812D01*
X146437Y448145D01*
X146645Y448353D01*
X146937Y448437D01*
X147228Y448353D01*
X147478Y448103D01*
X147603Y447728D01*
Y447312D01*
X147687Y447062D01*
X147895Y446853D01*
X148187Y446770D01*
X148478Y446895D01*
X148687Y447187D01*
X148770Y447520D01*
X148687Y447853D01*
X148478Y448145D01*
X148187Y448270D01*
X147895Y448187D01*
X147687Y447978D01*
X147603Y447728D01*
Y447312D01*
X147478Y446937D01*
X147228Y446687D01*
X146937Y446603D01*
X146645Y446687D01*
X146437Y446895D01*
X146312Y447228D01*
X146270Y447520D01*
G01Y451120D02*
X148770D01*
X146978Y449578D01*
Y451662D01*
G01X174700Y486500D02*
Y484000D01*
G01X175658Y486500D02*
X173742D01*
G01X172433Y484000D02*
Y486500D01*
X171433D01*
X171100Y486375D01*
X170850Y486083D01*
X170767Y485750D01*
X170850Y485417D01*
X171058Y485167D01*
X171433Y485042D01*
X172433D01*
G01X169292Y486083D02*
X169042Y486333D01*
X168750Y486458D01*
X168417Y486500D01*
X168000Y486417D01*
X167708Y486208D01*
X167625Y485958D01*
X167667Y485708D01*
X167833Y485500D01*
X168667Y485083D01*
X169042Y484792D01*
X169292Y484375D01*
X169375Y484000D01*
X167625D01*
G01X165400Y486500D02*
X165733Y486417D01*
X165983Y486208D01*
X166150Y485958D01*
X166275Y485625D01*
X166317Y485250D01*
X166275Y484875D01*
X166150Y484542D01*
X165983Y484292D01*
X165733Y484083D01*
X165400Y484000D01*
X165067Y484083D01*
X164817Y484292D01*
X164650Y484542D01*
X164525Y484875D01*
X164483Y485250D01*
X164525Y485625D01*
X164650Y485958D01*
X164817Y486208D01*
X165067Y486417D01*
X165400Y486500D01*
G01X163217Y484500D02*
X162967Y484208D01*
X162633Y484042D01*
X162258Y484000D01*
X161925Y484042D01*
X161592Y484250D01*
X161383Y484500D01*
X161342Y484750D01*
X161425Y485042D01*
X161717Y485250D01*
X162008Y485333D01*
X162383D01*
G01X162008D02*
X161758Y485458D01*
X161550Y485667D01*
X161467Y485917D01*
X161550Y486167D01*
X161758Y486375D01*
X162133Y486500D01*
X162508Y486458D01*
X162883Y486292D01*
G01X199117Y451700D02*
Y449908D01*
X198950Y449533D01*
X198617Y449283D01*
X198200Y449200D01*
X197783Y449283D01*
X197450Y449533D01*
X197283Y449908D01*
Y451700D01*
G01X195892Y451283D02*
X195642Y451533D01*
X195350Y451658D01*
X195017Y451700D01*
X194600Y451617D01*
X194308Y451408D01*
X194225Y451158D01*
X194267Y450908D01*
X194433Y450700D01*
X195267Y450283D01*
X195642Y449992D01*
X195892Y449575D01*
X195975Y449200D01*
X194225D01*
G01X192083D02*
X192000Y449742D01*
X191875Y450200D01*
X191708Y450617D01*
X191500Y451075D01*
X191167Y451700D01*
X192833D01*
G01X187800Y477050D02*
X195800D01*
Y465100D01*
X187800D01*
Y477050D01*
G01X193950Y465100D02*
X191950Y467100D01*
X189950Y465100D01*
G01X166150Y482500D02*
Y480000D01*
G01X167108Y482500D02*
X165192D01*
G01X163883Y480000D02*
Y482500D01*
X162883D01*
X162550Y482375D01*
X162300Y482083D01*
X162217Y481750D01*
X162300Y481417D01*
X162508Y481167D01*
X162883Y481042D01*
X163883D01*
G01X159950Y480000D02*
Y482500D01*
X160450Y482000D01*
G01Y480000D02*
X159450D01*
G01X157558Y480292D02*
X157267Y480083D01*
X156933Y480000D01*
X156600Y480083D01*
X156308Y480333D01*
X156100Y480708D01*
X156017Y481083D01*
Y481542D01*
X156100Y481917D01*
X156308Y482250D01*
X156558Y482417D01*
X156850Y482500D01*
X157183Y482417D01*
X157433Y482250D01*
X157600Y482000D01*
X157683Y481667D01*
X157600Y481375D01*
X157392Y481083D01*
X157142Y480917D01*
X156850Y480875D01*
X156517Y480958D01*
X156267Y481167D01*
X156017Y481542D01*
G01X189694Y538028D02*
X193694D01*
Y530628D01*
G01X149899Y513790D02*
X152399D01*
Y514831D01*
X152274Y515165D01*
X152107Y515373D01*
X151774Y515456D01*
X151441Y515373D01*
X151232Y515123D01*
X151107Y514831D01*
Y513790D01*
G01Y514831D02*
X149899Y515456D01*
G01X151982Y516931D02*
X152232Y517181D01*
X152357Y517473D01*
X152399Y517806D01*
X152316Y518223D01*
X152107Y518515D01*
X151857Y518598D01*
X151607Y518556D01*
X151399Y518390D01*
X150982Y517556D01*
X150691Y517181D01*
X150274Y516931D01*
X149899Y516848D01*
Y518598D01*
G01Y520823D02*
X149941Y521115D01*
X150066Y521448D01*
X150274Y521656D01*
X150566Y521740D01*
X150857Y521656D01*
X151107Y521406D01*
X151232Y521031D01*
Y520615D01*
X151316Y520365D01*
X151524Y520156D01*
X151816Y520073D01*
X152107Y520198D01*
X152316Y520490D01*
X152399Y520823D01*
X152316Y521156D01*
X152107Y521448D01*
X151816Y521573D01*
X151524Y521490D01*
X151316Y521281D01*
X151232Y521031D01*
Y520615D01*
X151107Y520240D01*
X150857Y519990D01*
X150566Y519906D01*
X150274Y519990D01*
X150066Y520198D01*
X149941Y520531D01*
X149899Y520823D01*
G01Y524423D02*
X152399D01*
X150607Y522881D01*
Y524965D01*
G01X169000Y515100D02*
X165000D01*
Y522500D01*
G01X148700Y524700D02*
X144700D01*
Y532100D01*
G01X168800Y508500D02*
X172800D01*
Y501100D01*
G01X158501Y558867D02*
X154501D01*
Y566267D01*
G01X215793Y561817D02*
Y564317D01*
X214752D01*
X214418Y564192D01*
X214210Y564025D01*
X214127Y563692D01*
X214210Y563359D01*
X214460Y563150D01*
X214752Y563025D01*
X215793D01*
G01X214752D02*
X214127Y561817D01*
G01X212777Y562317D02*
X212527Y562025D01*
X212193Y561859D01*
X211818Y561817D01*
X211485Y561859D01*
X211152Y562067D01*
X210943Y562317D01*
X210902Y562567D01*
X210985Y562859D01*
X211277Y563067D01*
X211568Y563150D01*
X211943D01*
G01X211568D02*
X211318Y563275D01*
X211110Y563484D01*
X211027Y563734D01*
X211110Y563984D01*
X211318Y564192D01*
X211693Y564317D01*
X212068Y564275D01*
X212443Y564109D01*
G01X209552Y562859D02*
X209260Y563150D01*
X209010Y563317D01*
X208677Y563400D01*
X208385Y563317D01*
X208177Y563150D01*
X208010Y562900D01*
X207968Y562609D01*
X208010Y562359D01*
X208177Y562109D01*
X208427Y561900D01*
X208718Y561817D01*
X209052Y561900D01*
X209343Y562150D01*
X209510Y562525D01*
X209552Y562942D01*
X209468Y563484D01*
X209343Y563775D01*
X209135Y564067D01*
X208843Y564275D01*
X208552Y564317D01*
X208260Y564234D01*
X208052Y564025D01*
G01X206577Y562317D02*
X206327Y562025D01*
X205993Y561859D01*
X205618Y561817D01*
X205285Y561859D01*
X204952Y562067D01*
X204743Y562317D01*
X204702Y562567D01*
X204785Y562859D01*
X205077Y563067D01*
X205368Y563150D01*
X205743D01*
G01X205368D02*
X205118Y563275D01*
X204910Y563484D01*
X204827Y563734D01*
X204910Y563984D01*
X205118Y564192D01*
X205493Y564317D01*
X205868Y564275D01*
X206243Y564109D01*
G01X198890Y561900D02*
X194890D01*
Y569300D01*
G01X160600Y523000D02*
X156600D01*
Y530400D01*
G01X169454Y525477D02*
X165454D01*
Y532877D01*
G01X165300Y525200D02*
X161300D01*
Y532600D01*
G01X151984Y534913D02*
Y537413D01*
X150943D01*
X150609Y537288D01*
X150401Y537121D01*
X150318Y536788D01*
X150401Y536455D01*
X150651Y536246D01*
X150943Y536121D01*
X151984D01*
G01X150943D02*
X150318Y534913D01*
G01X148968Y535413D02*
X148718Y535121D01*
X148384Y534955D01*
X148009Y534913D01*
X147676Y534955D01*
X147343Y535163D01*
X147134Y535413D01*
X147093Y535663D01*
X147176Y535955D01*
X147468Y536163D01*
X147759Y536246D01*
X148134D01*
G01X147759D02*
X147509Y536371D01*
X147301Y536580D01*
X147218Y536830D01*
X147301Y537080D01*
X147509Y537288D01*
X147884Y537413D01*
X148259Y537371D01*
X148634Y537205D01*
G01X145034Y534913D02*
X144951Y535455D01*
X144826Y535913D01*
X144659Y536330D01*
X144451Y536788D01*
X144118Y537413D01*
X145784D01*
G01X142643Y536996D02*
X142393Y537246D01*
X142101Y537371D01*
X141768Y537413D01*
X141351Y537330D01*
X141059Y537121D01*
X140976Y536871D01*
X141018Y536621D01*
X141184Y536413D01*
X142018Y535996D01*
X142393Y535705D01*
X142643Y535288D01*
X142726Y534913D01*
X140976D01*
G01X169500Y528700D02*
Y532700D01*
X176900D01*
G01Y501100D02*
X172900D01*
Y508500D01*
G01X154889Y518812D02*
Y522812D01*
X162289D01*
G01X180597Y520574D02*
Y523074D01*
X179556D01*
X179222Y522949D01*
X179014Y522782D01*
X178931Y522449D01*
X179014Y522116D01*
X179264Y521907D01*
X179556Y521782D01*
X180597D01*
G01X179556D02*
X178931Y520574D01*
G01X176664D02*
Y523074D01*
X177164Y522574D01*
G01Y520574D02*
X176164D01*
G01X173564D02*
X173272Y520616D01*
X172939Y520741D01*
X172731Y520949D01*
X172647Y521241D01*
X172731Y521532D01*
X172981Y521782D01*
X173356Y521907D01*
X173772D01*
X174022Y521991D01*
X174231Y522199D01*
X174314Y522491D01*
X174189Y522782D01*
X173897Y522991D01*
X173564Y523074D01*
X173231Y522991D01*
X172939Y522782D01*
X172814Y522491D01*
X172897Y522199D01*
X173106Y521991D01*
X173356Y521907D01*
X173772D01*
X174147Y521782D01*
X174397Y521532D01*
X174481Y521241D01*
X174397Y520949D01*
X174189Y520741D01*
X173856Y520616D01*
X173564Y520574D01*
G01X169964D02*
Y523074D01*
X171506Y521282D01*
X169422D01*
G01X176900Y528700D02*
Y524700D01*
X169500D01*
G01X191000Y514617D02*
X193500D01*
Y515658D01*
X193375Y515992D01*
X193208Y516200D01*
X192875Y516283D01*
X192542Y516200D01*
X192333Y515950D01*
X192208Y515658D01*
Y514617D01*
G01Y515658D02*
X191000Y516283D01*
G01Y518550D02*
X193500D01*
X193000Y518050D01*
G01X191000D02*
Y519050D01*
G01Y521650D02*
X191042Y521942D01*
X191167Y522275D01*
X191375Y522483D01*
X191667Y522567D01*
X191958Y522483D01*
X192208Y522233D01*
X192333Y521858D01*
Y521442D01*
X192417Y521192D01*
X192625Y520983D01*
X192917Y520900D01*
X193208Y521025D01*
X193417Y521317D01*
X193500Y521650D01*
X193417Y521983D01*
X193208Y522275D01*
X192917Y522400D01*
X192625Y522317D01*
X192417Y522108D01*
X192333Y521858D01*
Y521442D01*
X192208Y521067D01*
X191958Y520817D01*
X191667Y520733D01*
X191375Y520817D01*
X191167Y521025D01*
X191042Y521358D01*
X191000Y521650D01*
G01X191500Y523833D02*
X191208Y524083D01*
X191042Y524417D01*
X191000Y524792D01*
X191042Y525125D01*
X191250Y525458D01*
X191500Y525667D01*
X191750Y525708D01*
X192042Y525625D01*
X192250Y525333D01*
X192333Y525042D01*
Y524667D01*
G01Y525042D02*
X192458Y525292D01*
X192667Y525500D01*
X192917Y525583D01*
X193167Y525500D01*
X193375Y525292D01*
X193500Y524917D01*
X193458Y524542D01*
X193292Y524167D01*
G01X182280Y518045D02*
Y522045D01*
X189680D01*
G01X215753Y557817D02*
Y560317D01*
X214712D01*
X214378Y560192D01*
X214170Y560025D01*
X214087Y559692D01*
X214170Y559359D01*
X214420Y559150D01*
X214712Y559025D01*
X215753D01*
G01X214712D02*
X214087Y557817D01*
G01X212737Y558317D02*
X212487Y558025D01*
X212153Y557859D01*
X211778Y557817D01*
X211445Y557859D01*
X211112Y558067D01*
X210903Y558317D01*
X210862Y558567D01*
X210945Y558859D01*
X211237Y559067D01*
X211528Y559150D01*
X211903D01*
G01X211528D02*
X211278Y559275D01*
X211070Y559484D01*
X210987Y559734D01*
X211070Y559984D01*
X211278Y560192D01*
X211653Y560317D01*
X212028Y560275D01*
X212403Y560109D01*
G01X209637Y558192D02*
X209387Y557984D01*
X209095Y557859D01*
X208720Y557817D01*
X208345Y557900D01*
X208053Y558067D01*
X207845Y558359D01*
X207803Y558692D01*
X207887Y559025D01*
X208095Y559234D01*
X208387Y559400D01*
X208678Y559442D01*
X208970Y559400D01*
X209345Y559234D01*
X209220Y560317D01*
X208095D01*
G01X205703Y557817D02*
X205620Y558359D01*
X205495Y558817D01*
X205328Y559234D01*
X205120Y559692D01*
X204787Y560317D01*
X206453D01*
G01X202910Y557790D02*
X198910D01*
Y565190D01*
G01X209378Y537801D02*
X213378D01*
Y530401D01*
G01X181838Y534101D02*
Y538101D01*
X189238D01*
G01X164737Y507554D02*
X168737D01*
Y500154D01*
G01X177000Y508500D02*
X181000D01*
Y501100D01*
G01X205278Y537801D02*
X209278D01*
Y530401D01*
G01X181400Y526400D02*
X177400D01*
Y533800D01*
G01X185670Y526366D02*
X181670D01*
Y533766D01*
G01X160537Y507554D02*
X164537D01*
Y500154D01*
G01X209998Y509868D02*
Y512368D01*
X208957D01*
X208623Y512243D01*
X208415Y512076D01*
X208332Y511743D01*
X208415Y511410D01*
X208665Y511201D01*
X208957Y511076D01*
X209998D01*
G01X208957D02*
X208332Y509868D01*
G01X206857Y511951D02*
X206607Y512201D01*
X206315Y512326D01*
X205982Y512368D01*
X205565Y512285D01*
X205273Y512076D01*
X205190Y511826D01*
X205232Y511576D01*
X205398Y511368D01*
X206232Y510951D01*
X206607Y510660D01*
X206857Y510243D01*
X206940Y509868D01*
X205190D01*
G01X203673Y510160D02*
X203382Y509951D01*
X203048Y509868D01*
X202715Y509951D01*
X202423Y510201D01*
X202215Y510576D01*
X202132Y510951D01*
Y511410D01*
X202215Y511785D01*
X202423Y512118D01*
X202673Y512285D01*
X202965Y512368D01*
X203298Y512285D01*
X203548Y512118D01*
X203715Y511868D01*
X203798Y511535D01*
X203715Y511243D01*
X203507Y510951D01*
X203257Y510785D01*
X202965Y510743D01*
X202632Y510826D01*
X202382Y511035D01*
X202132Y511410D01*
G01X199365Y509868D02*
Y512368D01*
X200907Y510576D01*
X198823D01*
G01X204246Y503509D02*
Y499509D01*
X196846D01*
G01X172686Y511171D02*
Y515171D01*
X180086D01*
G01X198013Y530775D02*
X194013D01*
Y538175D01*
G01X186000Y496517D02*
X188500D01*
Y497558D01*
X188375Y497892D01*
X188208Y498100D01*
X187875Y498183D01*
X187542Y498100D01*
X187333Y497850D01*
X187208Y497558D01*
Y496517D01*
G01Y497558D02*
X186000Y498183D01*
G01X188083Y499658D02*
X188333Y499908D01*
X188458Y500200D01*
X188500Y500533D01*
X188417Y500950D01*
X188208Y501242D01*
X187958Y501325D01*
X187708Y501283D01*
X187500Y501117D01*
X187083Y500283D01*
X186792Y499908D01*
X186375Y499658D01*
X186000Y499575D01*
Y501325D01*
G01Y503550D02*
X186042Y503842D01*
X186167Y504175D01*
X186375Y504383D01*
X186667Y504467D01*
X186958Y504383D01*
X187208Y504133D01*
X187333Y503758D01*
Y503342D01*
X187417Y503092D01*
X187625Y502883D01*
X187917Y502800D01*
X188208Y502925D01*
X188417Y503217D01*
X188500Y503550D01*
X188417Y503883D01*
X188208Y504175D01*
X187917Y504300D01*
X187625Y504217D01*
X187417Y504008D01*
X187333Y503758D01*
Y503342D01*
X187208Y502967D01*
X186958Y502717D01*
X186667Y502633D01*
X186375Y502717D01*
X186167Y502925D01*
X186042Y503258D01*
X186000Y503550D01*
G01X187042Y505858D02*
X187333Y506150D01*
X187500Y506400D01*
X187583Y506733D01*
X187500Y507025D01*
X187333Y507233D01*
X187083Y507400D01*
X186792Y507442D01*
X186542Y507400D01*
X186292Y507233D01*
X186083Y506983D01*
X186000Y506692D01*
X186083Y506358D01*
X186333Y506067D01*
X186708Y505900D01*
X187125Y505858D01*
X187667Y505942D01*
X187958Y506067D01*
X188250Y506275D01*
X188458Y506567D01*
X188500Y506858D01*
X188417Y507150D01*
X188208Y507358D01*
G01X145103Y507389D02*
Y511389D01*
X152503D01*
G01X191700Y526500D02*
Y530500D01*
X199100D01*
G01X198031Y538194D02*
X202031D01*
Y530794D01*
G01X145247Y507187D02*
X149247D01*
Y499787D01*
G01X149351Y507197D02*
X153351D01*
Y499797D01*
G01X156294Y507554D02*
X160294D01*
Y500154D01*
G01X148600Y515300D02*
X144600D01*
Y522700D01*
G01X214760Y567970D02*
Y565470D01*
G01X215718Y567970D02*
X213802D01*
G01X212493Y565470D02*
Y567970D01*
X211493D01*
X211160Y567845D01*
X210910Y567553D01*
X210827Y567220D01*
X210910Y566887D01*
X211118Y566637D01*
X211493Y566512D01*
X212493D01*
G01X208643Y565470D02*
X208560Y566012D01*
X208435Y566470D01*
X208268Y566887D01*
X208060Y567345D01*
X207727Y567970D01*
X209393D01*
G01X205460Y565470D02*
X205168Y565512D01*
X204835Y565637D01*
X204627Y565845D01*
X204543Y566137D01*
X204627Y566428D01*
X204877Y566678D01*
X205252Y566803D01*
X205668D01*
X205918Y566887D01*
X206127Y567095D01*
X206210Y567387D01*
X206085Y567678D01*
X205793Y567887D01*
X205460Y567970D01*
X205127Y567887D01*
X204835Y567678D01*
X204710Y567387D01*
X204793Y567095D01*
X205002Y566887D01*
X205252Y566803D01*
X205668D01*
X206043Y566678D01*
X206293Y566428D01*
X206377Y566137D01*
X206293Y565845D01*
X206085Y565637D01*
X205752Y565512D01*
X205460Y565470D01*
G01X211191Y548047D02*
Y545547D01*
G01X212149Y548047D02*
X210233D01*
G01X208924Y545547D02*
Y548047D01*
X207924D01*
X207591Y547922D01*
X207341Y547630D01*
X207258Y547297D01*
X207341Y546964D01*
X207549Y546714D01*
X207924Y546589D01*
X208924D01*
G01X205074Y545547D02*
X204991Y546089D01*
X204866Y546547D01*
X204699Y546964D01*
X204491Y547422D01*
X204158Y548047D01*
X205824D01*
G01X202683Y547630D02*
X202433Y547880D01*
X202141Y548005D01*
X201808Y548047D01*
X201391Y547964D01*
X201099Y547755D01*
X201016Y547505D01*
X201058Y547255D01*
X201224Y547047D01*
X202058Y546630D01*
X202433Y546339D01*
X202683Y545922D01*
X202766Y545547D01*
X201016D01*
G01X176650Y545000D02*
Y542500D01*
G01X177608Y545000D02*
X175692D01*
G01X174383Y542500D02*
Y545000D01*
X173383D01*
X173050Y544875D01*
X172800Y544583D01*
X172717Y544250D01*
X172800Y543917D01*
X173008Y543667D01*
X173383Y543542D01*
X174383D01*
G01X171242Y544583D02*
X170992Y544833D01*
X170700Y544958D01*
X170367Y545000D01*
X169950Y544917D01*
X169658Y544708D01*
X169575Y544458D01*
X169617Y544208D01*
X169783Y544000D01*
X170617Y543583D01*
X170992Y543292D01*
X171242Y542875D01*
X171325Y542500D01*
X169575D01*
G01X168058Y542792D02*
X167767Y542583D01*
X167433Y542500D01*
X167100Y542583D01*
X166808Y542833D01*
X166600Y543208D01*
X166517Y543583D01*
Y544042D01*
X166600Y544417D01*
X166808Y544750D01*
X167058Y544917D01*
X167350Y545000D01*
X167683Y544917D01*
X167933Y544750D01*
X168100Y544500D01*
X168183Y544167D01*
X168100Y543875D01*
X167892Y543583D01*
X167642Y543417D01*
X167350Y543375D01*
X167017Y543458D01*
X166767Y543667D01*
X166517Y544042D01*
G01X170650Y555000D02*
Y552500D01*
G01X171608Y555000D02*
X169692D01*
G01X168383Y552500D02*
Y555000D01*
X167383D01*
X167050Y554875D01*
X166800Y554583D01*
X166717Y554250D01*
X166800Y553917D01*
X167008Y553667D01*
X167383Y553542D01*
X168383D01*
G01X165242Y554583D02*
X164992Y554833D01*
X164700Y554958D01*
X164367Y555000D01*
X163950Y554917D01*
X163658Y554708D01*
X163575Y554458D01*
X163617Y554208D01*
X163783Y554000D01*
X164617Y553583D01*
X164992Y553292D01*
X165242Y552875D01*
X165325Y552500D01*
X163575D01*
G01X161350D02*
X161058Y552542D01*
X160725Y552667D01*
X160517Y552875D01*
X160433Y553167D01*
X160517Y553458D01*
X160767Y553708D01*
X161142Y553833D01*
X161558D01*
X161808Y553917D01*
X162017Y554125D01*
X162100Y554417D01*
X161975Y554708D01*
X161683Y554917D01*
X161350Y555000D01*
X161017Y554917D01*
X160725Y554708D01*
X160600Y554417D01*
X160683Y554125D01*
X160892Y553917D01*
X161142Y553833D01*
X161558D01*
X161933Y553708D01*
X162183Y553458D01*
X162267Y553167D01*
X162183Y552875D01*
X161975Y552667D01*
X161642Y552542D01*
X161350Y552500D01*
G01X184105Y549088D02*
Y546588D01*
G01X185063Y549088D02*
X183147D01*
G01X181838Y546588D02*
Y549088D01*
X180838D01*
X180505Y548963D01*
X180255Y548671D01*
X180172Y548338D01*
X180255Y548005D01*
X180463Y547755D01*
X180838Y547630D01*
X181838D01*
G01X178697Y548671D02*
X178447Y548921D01*
X178155Y549046D01*
X177822Y549088D01*
X177405Y549005D01*
X177113Y548796D01*
X177030Y548546D01*
X177072Y548296D01*
X177238Y548088D01*
X178072Y547671D01*
X178447Y547380D01*
X178697Y546963D01*
X178780Y546588D01*
X177030D01*
G01X174888D02*
X174805Y547130D01*
X174680Y547588D01*
X174513Y548005D01*
X174305Y548463D01*
X173972Y549088D01*
X175638D01*
G01X162150Y545500D02*
Y543000D01*
G01X163108Y545500D02*
X161192D01*
G01X159883Y543000D02*
Y545500D01*
X158883D01*
X158550Y545375D01*
X158300Y545083D01*
X158217Y544750D01*
X158300Y544417D01*
X158508Y544167D01*
X158883Y544042D01*
X159883D01*
G01X155950Y543000D02*
Y545500D01*
X156450Y545000D01*
G01Y543000D02*
X155450D01*
G01X152933D02*
X152850Y543542D01*
X152725Y544000D01*
X152558Y544417D01*
X152350Y544875D01*
X152017Y545500D01*
X153683D01*
G01X211600Y494280D02*
X221600D01*
G01X211600Y507680D02*
Y494280D01*
G01X221600Y507680D02*
X211600D01*
G01X144000Y496100D02*
Y506100D01*
G01X197679Y554673D02*
X197929Y554798D01*
X198221Y554881D01*
X198554D01*
X198929Y554756D01*
X199221Y554548D01*
X199429Y554298D01*
X199596Y553881D01*
X199638Y553506D01*
X199554Y553131D01*
X199429Y552881D01*
X199179Y552631D01*
X198888Y552464D01*
X198596Y552381D01*
X198304D01*
X198013Y552464D01*
X197763Y552589D01*
X197554Y552756D01*
G01X195496Y552381D02*
Y554881D01*
X195996Y554381D01*
G01Y552381D02*
X194996D01*
G01X192396Y554881D02*
X192729Y554798D01*
X192979Y554589D01*
X193146Y554339D01*
X193271Y554006D01*
X193313Y553631D01*
X193271Y553256D01*
X193146Y552923D01*
X192979Y552673D01*
X192729Y552464D01*
X192396Y552381D01*
X192063Y552464D01*
X191813Y552673D01*
X191646Y552923D01*
X191521Y553256D01*
X191479Y553631D01*
X191521Y554006D01*
X191646Y554339D01*
X191813Y554589D01*
X192063Y554798D01*
X192396Y554881D01*
G01X189296D02*
X189629Y554798D01*
X189879Y554589D01*
X190046Y554339D01*
X190171Y554006D01*
X190213Y553631D01*
X190171Y553256D01*
X190046Y552923D01*
X189879Y552673D01*
X189629Y552464D01*
X189296Y552381D01*
X188963Y552464D01*
X188713Y552673D01*
X188546Y552923D01*
X188421Y553256D01*
X188379Y553631D01*
X188421Y554006D01*
X188546Y554339D01*
X188713Y554589D01*
X188963Y554798D01*
X189296Y554881D01*
G01X253189Y547044D02*
X251896D01*
X251895Y547045D01*
Y559987D01*
X256193D01*
Y573970D01*
X245000D01*
Y590000D01*
X217001D01*
X217000Y589999D01*
Y573500D01*
X205310D01*
G03X205300Y573490I0J-10D01*
G01Y569010D01*
G03X205310Y569000I10J0D01*
G01X217500D01*
Y554400D01*
G01X166584Y578186D02*
X166834Y578311D01*
X167126Y578394D01*
X167459D01*
X167834Y578269D01*
X168126Y578061D01*
X168334Y577811D01*
X168501Y577394D01*
X168543Y577019D01*
X168459Y576644D01*
X168334Y576394D01*
X168084Y576144D01*
X167793Y575977D01*
X167501Y575894D01*
X167209D01*
X166918Y575977D01*
X166668Y576102D01*
X166459Y576269D01*
G01X165318D02*
X165068Y576061D01*
X164776Y575936D01*
X164401Y575894D01*
X164026Y575977D01*
X163734Y576144D01*
X163526Y576436D01*
X163484Y576769D01*
X163568Y577102D01*
X163776Y577311D01*
X164068Y577477D01*
X164359Y577519D01*
X164651Y577477D01*
X165026Y577311D01*
X164901Y578394D01*
X163776D01*
G01X162218Y576394D02*
X161968Y576102D01*
X161634Y575936D01*
X161259Y575894D01*
X160926Y575936D01*
X160593Y576144D01*
X160384Y576394D01*
X160343Y576644D01*
X160426Y576936D01*
X160718Y577144D01*
X161009Y577227D01*
X161384D01*
G01X161009D02*
X160759Y577352D01*
X160551Y577561D01*
X160468Y577811D01*
X160551Y578061D01*
X160759Y578269D01*
X161134Y578394D01*
X161509Y578352D01*
X161884Y578186D01*
G01X153244Y575461D02*
X153494Y575586D01*
X153786Y575669D01*
X154119D01*
X154494Y575544D01*
X154786Y575336D01*
X154994Y575086D01*
X155161Y574669D01*
X155203Y574294D01*
X155119Y573919D01*
X154994Y573669D01*
X154744Y573419D01*
X154453Y573252D01*
X154161Y573169D01*
X153869D01*
X153578Y573252D01*
X153328Y573377D01*
X153119Y573544D01*
G01X151144Y573169D02*
X151061Y573711D01*
X150936Y574169D01*
X150769Y574586D01*
X150561Y575044D01*
X150228Y575669D01*
X151894D01*
G01X147961Y573169D02*
Y575669D01*
X148461Y575169D01*
G01Y573169D02*
X147461D01*
G01X166584Y582186D02*
X166834Y582311D01*
X167126Y582394D01*
X167459D01*
X167834Y582269D01*
X168126Y582061D01*
X168334Y581811D01*
X168501Y581394D01*
X168543Y581019D01*
X168459Y580644D01*
X168334Y580394D01*
X168084Y580144D01*
X167793Y579977D01*
X167501Y579894D01*
X167209D01*
X166918Y579977D01*
X166668Y580102D01*
X166459Y580269D01*
G01X165318D02*
X165068Y580061D01*
X164776Y579936D01*
X164401Y579894D01*
X164026Y579977D01*
X163734Y580144D01*
X163526Y580436D01*
X163484Y580769D01*
X163568Y581102D01*
X163776Y581311D01*
X164068Y581477D01*
X164359Y581519D01*
X164651Y581477D01*
X165026Y581311D01*
X164901Y582394D01*
X163776D01*
G01X162218Y580269D02*
X161968Y580061D01*
X161676Y579936D01*
X161301Y579894D01*
X160926Y579977D01*
X160634Y580144D01*
X160426Y580436D01*
X160384Y580769D01*
X160468Y581102D01*
X160676Y581311D01*
X160968Y581477D01*
X161259Y581519D01*
X161551Y581477D01*
X161926Y581311D01*
X161801Y582394D01*
X160676D01*
G01X209783Y612200D02*
Y614700D01*
X208742D01*
X208408Y614575D01*
X208200Y614408D01*
X208117Y614075D01*
X208200Y613742D01*
X208450Y613533D01*
X208742Y613408D01*
X209783D01*
G01X208742D02*
X208117Y612200D01*
G01X206767Y612700D02*
X206517Y612408D01*
X206183Y612242D01*
X205808Y612200D01*
X205475Y612242D01*
X205142Y612450D01*
X204933Y612700D01*
X204892Y612950D01*
X204975Y613242D01*
X205267Y613450D01*
X205558Y613533D01*
X205933D01*
G01X205558D02*
X205308Y613658D01*
X205100Y613867D01*
X205017Y614117D01*
X205100Y614367D01*
X205308Y614575D01*
X205683Y614700D01*
X206058Y614658D01*
X206433Y614492D01*
G01X203542Y613242D02*
X203250Y613533D01*
X203000Y613700D01*
X202667Y613783D01*
X202375Y613700D01*
X202167Y613533D01*
X202000Y613283D01*
X201958Y612992D01*
X202000Y612742D01*
X202167Y612492D01*
X202417Y612283D01*
X202708Y612200D01*
X203042Y612283D01*
X203333Y612533D01*
X203500Y612908D01*
X203542Y613325D01*
X203458Y613867D01*
X203333Y614158D01*
X203125Y614450D01*
X202833Y614658D01*
X202542Y614700D01*
X202250Y614617D01*
X202042Y614408D01*
G01X200442Y613242D02*
X200150Y613533D01*
X199900Y613700D01*
X199567Y613783D01*
X199275Y613700D01*
X199067Y613533D01*
X198900Y613283D01*
X198858Y612992D01*
X198900Y612742D01*
X199067Y612492D01*
X199317Y612283D01*
X199608Y612200D01*
X199942Y612283D01*
X200233Y612533D01*
X200400Y612908D01*
X200442Y613325D01*
X200358Y613867D01*
X200233Y614158D01*
X200025Y614450D01*
X199733Y614658D01*
X199442Y614700D01*
X199150Y614617D01*
X198942Y614408D01*
G01X206000Y610800D02*
Y606800D01*
X198600D01*
G01X142000Y569517D02*
X144500D01*
Y570558D01*
X144375Y570892D01*
X144208Y571100D01*
X143875Y571183D01*
X143542Y571100D01*
X143333Y570850D01*
X143208Y570558D01*
Y569517D01*
G01Y570558D02*
X142000Y571183D01*
G01Y573450D02*
X144500D01*
X144000Y572950D01*
G01X142000D02*
Y573950D01*
G01Y577050D02*
X144500D01*
X142708Y575508D01*
Y577592D01*
G01X142375Y578733D02*
X142167Y578983D01*
X142042Y579275D01*
X142000Y579650D01*
X142083Y580025D01*
X142250Y580317D01*
X142542Y580525D01*
X142875Y580567D01*
X143208Y580483D01*
X143417Y580275D01*
X143583Y579983D01*
X143625Y579692D01*
X143583Y579400D01*
X143417Y579025D01*
X144500Y579150D01*
Y580275D01*
G01X209800Y632500D02*
Y636500D01*
X217200D01*
G01X168334Y583894D02*
Y586394D01*
X167293D01*
X166959Y586269D01*
X166751Y586102D01*
X166668Y585769D01*
X166751Y585436D01*
X167001Y585227D01*
X167293Y585102D01*
X168334D01*
G01X167293D02*
X166668Y583894D01*
G01X164401D02*
Y586394D01*
X164901Y585894D01*
G01Y583894D02*
X163901D01*
G01X160801D02*
Y586394D01*
X162343Y584602D01*
X160259D01*
G01X159118Y584394D02*
X158868Y584102D01*
X158534Y583936D01*
X158159Y583894D01*
X157826Y583936D01*
X157493Y584144D01*
X157284Y584394D01*
X157243Y584644D01*
X157326Y584936D01*
X157618Y585144D01*
X157909Y585227D01*
X158284D01*
G01X157909D02*
X157659Y585352D01*
X157451Y585561D01*
X157368Y585811D01*
X157451Y586061D01*
X157659Y586269D01*
X158034Y586394D01*
X158409Y586352D01*
X158784Y586186D01*
G01X170087Y585147D02*
Y589147D01*
X177487D01*
G01X168334Y571894D02*
Y574394D01*
X167293D01*
X166959Y574269D01*
X166751Y574102D01*
X166668Y573769D01*
X166751Y573436D01*
X167001Y573227D01*
X167293Y573102D01*
X168334D01*
G01X167293D02*
X166668Y571894D01*
G01X164401D02*
Y574394D01*
X164901Y573894D01*
G01Y571894D02*
X163901D01*
G01X160801D02*
Y574394D01*
X162343Y572602D01*
X160259D01*
G01X158201Y571894D02*
Y574394D01*
X158701Y573894D01*
G01Y571894D02*
X157701D01*
G01X177802Y576058D02*
Y572058D01*
X170402D01*
G01X183483Y636500D02*
Y639000D01*
X182442D01*
X182108Y638875D01*
X181900Y638708D01*
X181817Y638375D01*
X181900Y638042D01*
X182150Y637833D01*
X182442Y637708D01*
X183483D01*
G01X182442D02*
X181817Y636500D01*
G01X180467Y637000D02*
X180217Y636708D01*
X179883Y636542D01*
X179508Y636500D01*
X179175Y636542D01*
X178842Y636750D01*
X178633Y637000D01*
X178592Y637250D01*
X178675Y637542D01*
X178967Y637750D01*
X179258Y637833D01*
X179633D01*
G01X179258D02*
X179008Y637958D01*
X178800Y638167D01*
X178717Y638417D01*
X178800Y638667D01*
X179008Y638875D01*
X179383Y639000D01*
X179758Y638958D01*
X180133Y638792D01*
G01X177242Y638583D02*
X176992Y638833D01*
X176700Y638958D01*
X176367Y639000D01*
X175950Y638917D01*
X175658Y638708D01*
X175575Y638458D01*
X175617Y638208D01*
X175783Y638000D01*
X176617Y637583D01*
X176992Y637292D01*
X177242Y636875D01*
X177325Y636500D01*
X175575D01*
G01X172850D02*
Y639000D01*
X174392Y637208D01*
X172308D01*
G01X182710Y615688D02*
Y619688D01*
X190110D01*
G01X184900Y621317D02*
X187400D01*
Y622358D01*
X187275Y622692D01*
X187108Y622900D01*
X186775Y622983D01*
X186442Y622900D01*
X186233Y622650D01*
X186108Y622358D01*
Y621317D01*
G01Y622358D02*
X184900Y622983D01*
G01X185400Y624333D02*
X185108Y624583D01*
X184942Y624917D01*
X184900Y625292D01*
X184942Y625625D01*
X185150Y625958D01*
X185400Y626167D01*
X185650Y626208D01*
X185942Y626125D01*
X186150Y625833D01*
X186233Y625542D01*
Y625167D01*
G01Y625542D02*
X186358Y625792D01*
X186567Y626000D01*
X186817Y626083D01*
X187067Y626000D01*
X187275Y625792D01*
X187400Y625417D01*
X187358Y625042D01*
X187192Y624667D01*
G01X186983Y627558D02*
X187233Y627808D01*
X187358Y628100D01*
X187400Y628433D01*
X187317Y628850D01*
X187108Y629142D01*
X186858Y629225D01*
X186608Y629183D01*
X186400Y629017D01*
X185983Y628183D01*
X185692Y627808D01*
X185275Y627558D01*
X184900Y627475D01*
Y629225D01*
G01X185400Y630533D02*
X185108Y630783D01*
X184942Y631117D01*
X184900Y631492D01*
X184942Y631825D01*
X185150Y632158D01*
X185400Y632367D01*
X185650Y632408D01*
X185942Y632325D01*
X186150Y632033D01*
X186233Y631742D01*
Y631367D01*
G01Y631742D02*
X186358Y631992D01*
X186567Y632200D01*
X186817Y632283D01*
X187067Y632200D01*
X187275Y631992D01*
X187400Y631617D01*
X187358Y631242D01*
X187192Y630867D01*
G01X190471Y616338D02*
X194471D01*
Y608938D01*
G01X175500Y621517D02*
X178000D01*
Y622558D01*
X177875Y622892D01*
X177708Y623100D01*
X177375Y623183D01*
X177042Y623100D01*
X176833Y622850D01*
X176708Y622558D01*
Y621517D01*
G01Y622558D02*
X175500Y623183D01*
G01X176000Y624533D02*
X175708Y624783D01*
X175542Y625117D01*
X175500Y625492D01*
X175542Y625825D01*
X175750Y626158D01*
X176000Y626367D01*
X176250Y626408D01*
X176542Y626325D01*
X176750Y626033D01*
X176833Y625742D01*
Y625367D01*
G01Y625742D02*
X176958Y625992D01*
X177167Y626200D01*
X177417Y626283D01*
X177667Y626200D01*
X177875Y625992D01*
X178000Y625617D01*
X177958Y625242D01*
X177792Y624867D01*
G01X175500Y628550D02*
X178000D01*
X177500Y628050D01*
G01X175500D02*
Y629050D01*
G01Y631650D02*
X178000D01*
X177500Y631150D01*
G01X175500D02*
Y632150D01*
G01X186400Y605900D02*
X182400D01*
Y613300D01*
G01X179000Y624017D02*
X181500D01*
Y625058D01*
X181375Y625392D01*
X181208Y625600D01*
X180875Y625683D01*
X180542Y625600D01*
X180333Y625350D01*
X180208Y625058D01*
Y624017D01*
G01Y625058D02*
X179000Y625683D01*
G01X179500Y627033D02*
X179208Y627283D01*
X179042Y627617D01*
X179000Y627992D01*
X179042Y628325D01*
X179250Y628658D01*
X179500Y628867D01*
X179750Y628908D01*
X180042Y628825D01*
X180250Y628533D01*
X180333Y628242D01*
Y627867D01*
G01Y628242D02*
X180458Y628492D01*
X180667Y628700D01*
X180917Y628783D01*
X181167Y628700D01*
X181375Y628492D01*
X181500Y628117D01*
X181458Y627742D01*
X181292Y627367D01*
G01X179000Y631050D02*
X181500D01*
X181000Y630550D01*
G01X179000D02*
Y631550D01*
G01X181500Y634150D02*
X181417Y633817D01*
X181208Y633567D01*
X180958Y633400D01*
X180625Y633275D01*
X180250Y633233D01*
X179875Y633275D01*
X179542Y633400D01*
X179292Y633567D01*
X179083Y633817D01*
X179000Y634150D01*
X179083Y634483D01*
X179292Y634733D01*
X179542Y634900D01*
X179875Y635025D01*
X180250Y635067D01*
X180625Y635025D01*
X180958Y634900D01*
X181208Y634733D01*
X181417Y634483D01*
X181500Y634150D01*
G01X186431Y615338D02*
X190431D01*
Y607938D01*
G01X204155Y627814D02*
Y623814D01*
X196755D01*
G01X209200Y616017D02*
X211700D01*
Y617058D01*
X211575Y617392D01*
X211408Y617600D01*
X211075Y617683D01*
X210742Y617600D01*
X210533Y617350D01*
X210408Y617058D01*
Y616017D01*
G01Y617058D02*
X209200Y617683D01*
G01X209700Y619033D02*
X209408Y619283D01*
X209242Y619617D01*
X209200Y619992D01*
X209242Y620325D01*
X209450Y620658D01*
X209700Y620867D01*
X209950Y620908D01*
X210242Y620825D01*
X210450Y620533D01*
X210533Y620242D01*
Y619867D01*
G01Y620242D02*
X210658Y620492D01*
X210867Y620700D01*
X211117Y620783D01*
X211367Y620700D01*
X211575Y620492D01*
X211700Y620117D01*
X211658Y619742D01*
X211492Y619367D01*
G01X209200Y623050D02*
X211700D01*
X211200Y622550D01*
G01X209200D02*
Y623550D01*
G01X209575Y625233D02*
X209367Y625483D01*
X209242Y625775D01*
X209200Y626150D01*
X209283Y626525D01*
X209450Y626817D01*
X209742Y627025D01*
X210075Y627067D01*
X210408Y626983D01*
X210617Y626775D01*
X210783Y626483D01*
X210825Y626192D01*
X210783Y625900D01*
X210617Y625525D01*
X211700Y625650D01*
Y626775D01*
G01X214500Y606500D02*
X210500D01*
Y613900D01*
G01X168983Y627500D02*
Y630000D01*
X167942D01*
X167608Y629875D01*
X167400Y629708D01*
X167317Y629375D01*
X167400Y629042D01*
X167650Y628833D01*
X167942Y628708D01*
X168983D01*
G01X167942D02*
X167317Y627500D01*
G01X165967Y628000D02*
X165717Y627708D01*
X165383Y627542D01*
X165008Y627500D01*
X164675Y627542D01*
X164342Y627750D01*
X164133Y628000D01*
X164092Y628250D01*
X164175Y628542D01*
X164467Y628750D01*
X164758Y628833D01*
X165133D01*
G01X164758D02*
X164508Y628958D01*
X164300Y629167D01*
X164217Y629417D01*
X164300Y629667D01*
X164508Y629875D01*
X164883Y630000D01*
X165258Y629958D01*
X165633Y629792D01*
G01X162742Y629583D02*
X162492Y629833D01*
X162200Y629958D01*
X161867Y630000D01*
X161450Y629917D01*
X161158Y629708D01*
X161075Y629458D01*
X161117Y629208D01*
X161283Y629000D01*
X162117Y628583D01*
X162492Y628292D01*
X162742Y627875D01*
X162825Y627500D01*
X161075D01*
G01X159642Y628542D02*
X159350Y628833D01*
X159100Y629000D01*
X158767Y629083D01*
X158475Y629000D01*
X158267Y628833D01*
X158100Y628583D01*
X158058Y628292D01*
X158100Y628042D01*
X158267Y627792D01*
X158517Y627583D01*
X158808Y627500D01*
X159142Y627583D01*
X159433Y627833D01*
X159600Y628208D01*
X159642Y628625D01*
X159558Y629167D01*
X159433Y629458D01*
X159225Y629750D01*
X158933Y629958D01*
X158642Y630000D01*
X158350Y629917D01*
X158142Y629708D01*
G01X165100Y621900D02*
Y617900D01*
X157700D01*
G01X154957Y604562D02*
Y600562D01*
X147557D01*
G01X151200Y598700D02*
Y594700D01*
X143800D01*
G01X154000Y619517D02*
X156500D01*
Y620558D01*
X156375Y620892D01*
X156208Y621100D01*
X155875Y621183D01*
X155542Y621100D01*
X155333Y620850D01*
X155208Y620558D01*
Y619517D01*
G01Y620558D02*
X154000Y621183D01*
G01X154500Y622533D02*
X154208Y622783D01*
X154042Y623117D01*
X154000Y623492D01*
X154042Y623825D01*
X154250Y624158D01*
X154500Y624367D01*
X154750Y624408D01*
X155042Y624325D01*
X155250Y624033D01*
X155333Y623742D01*
Y623367D01*
G01Y623742D02*
X155458Y623992D01*
X155667Y624200D01*
X155917Y624283D01*
X156167Y624200D01*
X156375Y623992D01*
X156500Y623617D01*
X156458Y623242D01*
X156292Y622867D01*
G01X154000Y626550D02*
X156500D01*
X156000Y626050D01*
G01X154000D02*
Y627050D01*
G01X155042Y628858D02*
X155333Y629150D01*
X155500Y629400D01*
X155583Y629733D01*
X155500Y630025D01*
X155333Y630233D01*
X155083Y630400D01*
X154792Y630442D01*
X154542Y630400D01*
X154292Y630233D01*
X154083Y629983D01*
X154000Y629692D01*
X154083Y629358D01*
X154333Y629067D01*
X154708Y628900D01*
X155125Y628858D01*
X155667Y628942D01*
X155958Y629067D01*
X156250Y629275D01*
X156458Y629567D01*
X156500Y629858D01*
X156417Y630150D01*
X156208Y630358D01*
G01X157341Y611172D02*
X153341D01*
Y618572D01*
G01X188700Y621317D02*
X191200D01*
Y622358D01*
X191075Y622692D01*
X190908Y622900D01*
X190575Y622983D01*
X190242Y622900D01*
X190033Y622650D01*
X189908Y622358D01*
Y621317D01*
G01Y622358D02*
X188700Y622983D01*
G01X190783Y624458D02*
X191033Y624708D01*
X191158Y625000D01*
X191200Y625333D01*
X191117Y625750D01*
X190908Y626042D01*
X190658Y626125D01*
X190408Y626083D01*
X190200Y625917D01*
X189783Y625083D01*
X189492Y624708D01*
X189075Y624458D01*
X188700Y624375D01*
Y626125D01*
G01X188992Y627642D02*
X188783Y627933D01*
X188700Y628267D01*
X188783Y628600D01*
X189033Y628892D01*
X189408Y629100D01*
X189783Y629183D01*
X190242D01*
X190617Y629100D01*
X190950Y628892D01*
X191117Y628642D01*
X191200Y628350D01*
X191117Y628017D01*
X190950Y627767D01*
X190700Y627600D01*
X190367Y627517D01*
X190075Y627600D01*
X189783Y627808D01*
X189617Y628058D01*
X189575Y628350D01*
X189658Y628683D01*
X189867Y628933D01*
X190242Y629183D01*
G01X188700Y631450D02*
X188742Y631742D01*
X188867Y632075D01*
X189075Y632283D01*
X189367Y632367D01*
X189658Y632283D01*
X189908Y632033D01*
X190033Y631658D01*
Y631242D01*
X190117Y630992D01*
X190325Y630783D01*
X190617Y630700D01*
X190908Y630825D01*
X191117Y631117D01*
X191200Y631450D01*
X191117Y631783D01*
X190908Y632075D01*
X190617Y632200D01*
X190325Y632117D01*
X190117Y631908D01*
X190033Y631658D01*
Y631242D01*
X189908Y630867D01*
X189658Y630617D01*
X189367Y630533D01*
X189075Y630617D01*
X188867Y630825D01*
X188742Y631158D01*
X188700Y631450D01*
G01X198500Y605900D02*
X194500D01*
Y613300D01*
G01X196718Y620594D02*
X192718D01*
Y627994D01*
G01X209400Y640200D02*
Y636200D01*
X202000D01*
G01X184704Y634190D02*
Y638190D01*
X192104D01*
G01X192170Y634210D02*
Y638210D01*
X199570D01*
G01X150000Y626017D02*
X152500D01*
Y627058D01*
X152375Y627392D01*
X152208Y627600D01*
X151875Y627683D01*
X151542Y627600D01*
X151333Y627350D01*
X151208Y627058D01*
Y626017D01*
G01Y627058D02*
X150000Y627683D01*
G01Y629867D02*
X150542Y629950D01*
X151000Y630075D01*
X151417Y630242D01*
X151875Y630450D01*
X152500Y630783D01*
Y629117D01*
G01X150000Y632967D02*
X150542Y633050D01*
X151000Y633175D01*
X151417Y633342D01*
X151875Y633550D01*
X152500Y633883D01*
Y632217D01*
G01X150000Y636067D02*
X150542Y636150D01*
X151000Y636275D01*
X151417Y636442D01*
X151875Y636650D01*
X152500Y636983D01*
Y635317D01*
G01X145723Y617596D02*
X149723D01*
Y610196D01*
G01X169883Y636100D02*
Y638600D01*
X168842D01*
X168508Y638475D01*
X168300Y638308D01*
X168217Y637975D01*
X168300Y637642D01*
X168550Y637433D01*
X168842Y637308D01*
X169883D01*
G01X168842D02*
X168217Y636100D01*
G01X166742Y637142D02*
X166450Y637433D01*
X166200Y637600D01*
X165867Y637683D01*
X165575Y637600D01*
X165367Y637433D01*
X165200Y637183D01*
X165158Y636892D01*
X165200Y636642D01*
X165367Y636392D01*
X165617Y636183D01*
X165908Y636100D01*
X166242Y636183D01*
X166533Y636433D01*
X166700Y636808D01*
X166742Y637225D01*
X166658Y637767D01*
X166533Y638058D01*
X166325Y638350D01*
X166033Y638558D01*
X165742Y638600D01*
X165450Y638517D01*
X165242Y638308D01*
G01X163558Y636392D02*
X163267Y636183D01*
X162933Y636100D01*
X162600Y636183D01*
X162308Y636433D01*
X162100Y636808D01*
X162017Y637183D01*
Y637642D01*
X162100Y638017D01*
X162308Y638350D01*
X162558Y638517D01*
X162850Y638600D01*
X163183Y638517D01*
X163433Y638350D01*
X163600Y638100D01*
X163683Y637767D01*
X163600Y637475D01*
X163392Y637183D01*
X163142Y637017D01*
X162850Y636975D01*
X162517Y637058D01*
X162267Y637267D01*
X162017Y637642D01*
G01X159833Y636100D02*
X159750Y636642D01*
X159625Y637100D01*
X159458Y637517D01*
X159250Y637975D01*
X158917Y638600D01*
X160583D01*
G01X181434Y621120D02*
Y617120D01*
X174034D01*
G01X146300Y588500D02*
Y592500D01*
X153700D01*
G01X199483Y590500D02*
Y593000D01*
X198442D01*
X198108Y592875D01*
X197900Y592708D01*
X197817Y592375D01*
X197900Y592042D01*
X198150Y591833D01*
X198442Y591708D01*
X199483D01*
G01X198442D02*
X197817Y590500D01*
G01X195633D02*
X195550Y591042D01*
X195425Y591500D01*
X195258Y591917D01*
X195050Y592375D01*
X194717Y593000D01*
X196383D01*
G01X192450D02*
X192783Y592917D01*
X193033Y592708D01*
X193200Y592458D01*
X193325Y592125D01*
X193367Y591750D01*
X193325Y591375D01*
X193200Y591042D01*
X193033Y590792D01*
X192783Y590583D01*
X192450Y590500D01*
X192117Y590583D01*
X191867Y590792D01*
X191700Y591042D01*
X191575Y591375D01*
X191533Y591750D01*
X191575Y592125D01*
X191700Y592458D01*
X191867Y592708D01*
X192117Y592917D01*
X192450Y593000D01*
G01X189433Y590500D02*
X189350Y591042D01*
X189225Y591500D01*
X189058Y591917D01*
X188850Y592375D01*
X188517Y593000D01*
X190183D01*
G01X186700Y585600D02*
X182700D01*
Y593000D01*
G01X153000Y622200D02*
Y618200D01*
X145600D01*
G01X176650Y599267D02*
Y596767D01*
G01X177608Y599267D02*
X175692D01*
G01X174383Y596767D02*
Y599267D01*
X173383D01*
X173050Y599142D01*
X172800Y598850D01*
X172717Y598517D01*
X172800Y598184D01*
X173008Y597934D01*
X173383Y597809D01*
X174383D01*
G01X171242D02*
X170950Y598100D01*
X170700Y598267D01*
X170367Y598350D01*
X170075Y598267D01*
X169867Y598100D01*
X169700Y597850D01*
X169658Y597559D01*
X169700Y597309D01*
X169867Y597059D01*
X170117Y596850D01*
X170408Y596767D01*
X170742Y596850D01*
X171033Y597100D01*
X171200Y597475D01*
X171242Y597892D01*
X171158Y598434D01*
X171033Y598725D01*
X170825Y599017D01*
X170533Y599225D01*
X170242Y599267D01*
X169950Y599184D01*
X169742Y598975D01*
G01X168142Y597809D02*
X167850Y598100D01*
X167600Y598267D01*
X167267Y598350D01*
X166975Y598267D01*
X166767Y598100D01*
X166600Y597850D01*
X166558Y597559D01*
X166600Y597309D01*
X166767Y597059D01*
X167017Y596850D01*
X167308Y596767D01*
X167642Y596850D01*
X167933Y597100D01*
X168100Y597475D01*
X168142Y597892D01*
X168058Y598434D01*
X167933Y598725D01*
X167725Y599017D01*
X167433Y599225D01*
X167142Y599267D01*
X166850Y599184D01*
X166642Y598975D01*
G01X161373Y588306D02*
X158873D01*
G01X161373Y587348D02*
Y589264D01*
G01X158873Y590573D02*
X161373D01*
Y591573D01*
X161248Y591906D01*
X160956Y592156D01*
X160623Y592239D01*
X160290Y592156D01*
X160040Y591948D01*
X159915Y591573D01*
Y590573D01*
G01Y593714D02*
X160206Y594006D01*
X160373Y594256D01*
X160456Y594589D01*
X160373Y594881D01*
X160206Y595089D01*
X159956Y595256D01*
X159665Y595298D01*
X159415Y595256D01*
X159165Y595089D01*
X158956Y594839D01*
X158873Y594548D01*
X158956Y594214D01*
X159206Y593923D01*
X159581Y593756D01*
X159998Y593714D01*
X160540Y593798D01*
X160831Y593923D01*
X161123Y594131D01*
X161331Y594423D01*
X161373Y594714D01*
X161290Y595006D01*
X161081Y595214D01*
G01X159248Y596689D02*
X159040Y596939D01*
X158915Y597231D01*
X158873Y597606D01*
X158956Y597981D01*
X159123Y598273D01*
X159415Y598481D01*
X159748Y598523D01*
X160081Y598439D01*
X160290Y598231D01*
X160456Y597939D01*
X160498Y597648D01*
X160456Y597356D01*
X160290Y596981D01*
X161373Y597106D01*
Y598231D01*
G01X176650Y595667D02*
Y593167D01*
G01X177608Y595667D02*
X175692D01*
G01X174383Y593167D02*
Y595667D01*
X173383D01*
X173050Y595542D01*
X172800Y595250D01*
X172717Y594917D01*
X172800Y594584D01*
X173008Y594334D01*
X173383Y594209D01*
X174383D01*
G01X171242D02*
X170950Y594500D01*
X170700Y594667D01*
X170367Y594750D01*
X170075Y594667D01*
X169867Y594500D01*
X169700Y594250D01*
X169658Y593959D01*
X169700Y593709D01*
X169867Y593459D01*
X170117Y593250D01*
X170408Y593167D01*
X170742Y593250D01*
X171033Y593500D01*
X171200Y593875D01*
X171242Y594292D01*
X171158Y594834D01*
X171033Y595125D01*
X170825Y595417D01*
X170533Y595625D01*
X170242Y595667D01*
X169950Y595584D01*
X169742Y595375D01*
G01X168267Y593667D02*
X168017Y593375D01*
X167683Y593209D01*
X167308Y593167D01*
X166975Y593209D01*
X166642Y593417D01*
X166433Y593667D01*
X166392Y593917D01*
X166475Y594209D01*
X166767Y594417D01*
X167058Y594500D01*
X167433D01*
G01X167058D02*
X166808Y594625D01*
X166600Y594834D01*
X166517Y595084D01*
X166600Y595334D01*
X166808Y595542D01*
X167183Y595667D01*
X167558Y595625D01*
X167933Y595459D01*
G01X165067Y591550D02*
X162567D01*
G01X165067Y590592D02*
Y592508D01*
G01X162567Y593817D02*
X165067D01*
Y594817D01*
X164942Y595150D01*
X164650Y595400D01*
X164317Y595483D01*
X163984Y595400D01*
X163734Y595192D01*
X163609Y594817D01*
Y593817D01*
G01Y596958D02*
X163900Y597250D01*
X164067Y597500D01*
X164150Y597833D01*
X164067Y598125D01*
X163900Y598333D01*
X163650Y598500D01*
X163359Y598542D01*
X163109Y598500D01*
X162859Y598333D01*
X162650Y598083D01*
X162567Y597792D01*
X162650Y597458D01*
X162900Y597167D01*
X163275Y597000D01*
X163692Y596958D01*
X164234Y597042D01*
X164525Y597167D01*
X164817Y597375D01*
X165025Y597667D01*
X165067Y597958D01*
X164984Y598250D01*
X164775Y598458D01*
G01X164650Y600058D02*
X164900Y600308D01*
X165025Y600600D01*
X165067Y600933D01*
X164984Y601350D01*
X164775Y601642D01*
X164525Y601725D01*
X164275Y601683D01*
X164067Y601517D01*
X163650Y600683D01*
X163359Y600308D01*
X162942Y600058D01*
X162567Y599975D01*
Y601725D01*
G01X215150Y583000D02*
Y580500D01*
G01X216108Y583000D02*
X214192D01*
G01X212883Y580500D02*
Y583000D01*
X211883D01*
X211550Y582875D01*
X211300Y582583D01*
X211217Y582250D01*
X211300Y581917D01*
X211508Y581667D01*
X211883Y581542D01*
X212883D01*
G01X209867Y580875D02*
X209617Y580667D01*
X209325Y580542D01*
X208950Y580500D01*
X208575Y580583D01*
X208283Y580750D01*
X208075Y581042D01*
X208033Y581375D01*
X208117Y581708D01*
X208325Y581917D01*
X208617Y582083D01*
X208908Y582125D01*
X209200Y582083D01*
X209575Y581917D01*
X209450Y583000D01*
X208325D01*
G01X205850Y580500D02*
Y583000D01*
X206350Y582500D01*
G01Y580500D02*
X205350D01*
G01X177200Y603300D02*
X174700D01*
G01X177200Y602342D02*
Y604258D01*
G01X174700Y605567D02*
X177200D01*
Y606567D01*
X177075Y606900D01*
X176783Y607150D01*
X176450Y607233D01*
X176117Y607150D01*
X175867Y606942D01*
X175742Y606567D01*
Y605567D01*
G01X174700Y609500D02*
X177200D01*
X176700Y609000D01*
G01X174700D02*
Y610000D01*
G01X174992Y611892D02*
X174783Y612183D01*
X174700Y612517D01*
X174783Y612850D01*
X175033Y613142D01*
X175408Y613350D01*
X175783Y613433D01*
X176242D01*
X176617Y613350D01*
X176950Y613142D01*
X177117Y612892D01*
X177200Y612600D01*
X177117Y612267D01*
X176950Y612017D01*
X176700Y611850D01*
X176367Y611767D01*
X176075Y611850D01*
X175783Y612058D01*
X175617Y612308D01*
X175575Y612600D01*
X175658Y612933D01*
X175867Y613183D01*
X176242Y613433D01*
G01X174700Y615700D02*
X177200D01*
X176700Y615200D01*
G01X174700D02*
Y616200D01*
G01X199800Y601200D02*
Y598700D01*
G01X200758Y601200D02*
X198842D01*
G01X197533Y598700D02*
Y601200D01*
X196533D01*
X196200Y601075D01*
X195950Y600783D01*
X195867Y600450D01*
X195950Y600117D01*
X196158Y599867D01*
X196533Y599742D01*
X197533D01*
G01X193600Y598700D02*
Y601200D01*
X194100Y600700D01*
G01Y598700D02*
X193100D01*
G01X191208Y598992D02*
X190917Y598783D01*
X190583Y598700D01*
X190250Y598783D01*
X189958Y599033D01*
X189750Y599408D01*
X189667Y599783D01*
Y600242D01*
X189750Y600617D01*
X189958Y600950D01*
X190208Y601117D01*
X190500Y601200D01*
X190833Y601117D01*
X191083Y600950D01*
X191250Y600700D01*
X191333Y600367D01*
X191250Y600075D01*
X191042Y599783D01*
X190792Y599617D01*
X190500Y599575D01*
X190167Y599658D01*
X189917Y599867D01*
X189667Y600242D01*
G01X187400Y601200D02*
X187733Y601117D01*
X187983Y600908D01*
X188150Y600658D01*
X188275Y600325D01*
X188317Y599950D01*
X188275Y599575D01*
X188150Y599242D01*
X187983Y598992D01*
X187733Y598783D01*
X187400Y598700D01*
X187067Y598783D01*
X186817Y598992D01*
X186650Y599242D01*
X186525Y599575D01*
X186483Y599950D01*
X186525Y600325D01*
X186650Y600658D01*
X186817Y600908D01*
X187067Y601117D01*
X187400Y601200D01*
G01X212888Y597190D02*
Y594690D01*
G01X213846Y597190D02*
X211930D01*
G01X210621Y594690D02*
Y597190D01*
X209621D01*
X209288Y597065D01*
X209038Y596773D01*
X208955Y596440D01*
X209038Y596107D01*
X209246Y595857D01*
X209621Y595732D01*
X210621D01*
G01X207480Y596773D02*
X207230Y597023D01*
X206938Y597148D01*
X206605Y597190D01*
X206188Y597107D01*
X205896Y596898D01*
X205813Y596648D01*
X205855Y596398D01*
X206021Y596190D01*
X206855Y595773D01*
X207230Y595482D01*
X207480Y595065D01*
X207563Y594690D01*
X205813D01*
G01X203588Y597190D02*
X203921Y597107D01*
X204171Y596898D01*
X204338Y596648D01*
X204463Y596315D01*
X204505Y595940D01*
X204463Y595565D01*
X204338Y595232D01*
X204171Y594982D01*
X203921Y594773D01*
X203588Y594690D01*
X203255Y594773D01*
X203005Y594982D01*
X202838Y595232D01*
X202713Y595565D01*
X202671Y595940D01*
X202713Y596315D01*
X202838Y596648D01*
X203005Y596898D01*
X203255Y597107D01*
X203588Y597190D01*
G01X201196Y594982D02*
X200905Y594773D01*
X200571Y594690D01*
X200238Y594773D01*
X199946Y595023D01*
X199738Y595398D01*
X199655Y595773D01*
Y596232D01*
X199738Y596607D01*
X199946Y596940D01*
X200196Y597107D01*
X200488Y597190D01*
X200821Y597107D01*
X201071Y596940D01*
X201238Y596690D01*
X201321Y596357D01*
X201238Y596065D01*
X201030Y595773D01*
X200780Y595607D01*
X200488Y595565D01*
X200155Y595648D01*
X199905Y595857D01*
X199655Y596232D01*
G01X218200Y631700D02*
Y629200D01*
G01X219158Y631700D02*
X217242D01*
G01X215933Y629200D02*
Y631700D01*
X214933D01*
X214600Y631575D01*
X214350Y631283D01*
X214267Y630950D01*
X214350Y630617D01*
X214558Y630367D01*
X214933Y630242D01*
X215933D01*
G01X212792Y631283D02*
X212542Y631533D01*
X212250Y631658D01*
X211917Y631700D01*
X211500Y631617D01*
X211208Y631408D01*
X211125Y631158D01*
X211167Y630908D01*
X211333Y630700D01*
X212167Y630283D01*
X212542Y629992D01*
X212792Y629575D01*
X212875Y629200D01*
X211125D01*
G01X208900D02*
Y631700D01*
X209400Y631200D01*
G01Y629200D02*
X208400D01*
G01X205800D02*
X205508Y629242D01*
X205175Y629367D01*
X204967Y629575D01*
X204883Y629867D01*
X204967Y630158D01*
X205217Y630408D01*
X205592Y630533D01*
X206008D01*
X206258Y630617D01*
X206467Y630825D01*
X206550Y631117D01*
X206425Y631408D01*
X206133Y631617D01*
X205800Y631700D01*
X205467Y631617D01*
X205175Y631408D01*
X205050Y631117D01*
X205133Y630825D01*
X205342Y630617D01*
X205592Y630533D01*
X206008D01*
X206383Y630408D01*
X206633Y630158D01*
X206717Y629867D01*
X206633Y629575D01*
X206425Y629367D01*
X206092Y629242D01*
X205800Y629200D01*
G01X193422Y573667D02*
X193547Y573417D01*
X193630Y573125D01*
Y572792D01*
X193505Y572417D01*
X193297Y572125D01*
X193047Y571917D01*
X192630Y571750D01*
X192255Y571708D01*
X191880Y571792D01*
X191630Y571917D01*
X191380Y572167D01*
X191213Y572458D01*
X191130Y572750D01*
Y573042D01*
X191213Y573333D01*
X191338Y573583D01*
X191505Y573792D01*
G01X191422Y575142D02*
X191213Y575433D01*
X191130Y575767D01*
X191213Y576100D01*
X191463Y576392D01*
X191838Y576600D01*
X192213Y576683D01*
X192672D01*
X193047Y576600D01*
X193380Y576392D01*
X193547Y576142D01*
X193630Y575850D01*
X193547Y575517D01*
X193380Y575267D01*
X193130Y575100D01*
X192797Y575017D01*
X192505Y575100D01*
X192213Y575308D01*
X192047Y575558D01*
X192005Y575850D01*
X192088Y576183D01*
X192297Y576433D01*
X192672Y576683D01*
G01X191130Y578950D02*
X191172Y579242D01*
X191297Y579575D01*
X191505Y579783D01*
X191797Y579867D01*
X192088Y579783D01*
X192338Y579533D01*
X192463Y579158D01*
Y578742D01*
X192547Y578492D01*
X192755Y578283D01*
X193047Y578200D01*
X193338Y578325D01*
X193547Y578617D01*
X193630Y578950D01*
X193547Y579283D01*
X193338Y579575D01*
X193047Y579700D01*
X192755Y579617D01*
X192547Y579408D01*
X192463Y579158D01*
Y578742D01*
X192338Y578367D01*
X192088Y578117D01*
X191797Y578033D01*
X191505Y578117D01*
X191297Y578325D01*
X191172Y578658D01*
X191130Y578950D01*
G01X169283Y568792D02*
X169533Y568917D01*
X169825Y569000D01*
X170158D01*
X170533Y568875D01*
X170825Y568667D01*
X171033Y568417D01*
X171200Y568000D01*
X171242Y567625D01*
X171158Y567250D01*
X171033Y567000D01*
X170783Y566750D01*
X170492Y566583D01*
X170200Y566500D01*
X169908D01*
X169617Y566583D01*
X169367Y566708D01*
X169158Y566875D01*
G01X168017D02*
X167767Y566667D01*
X167475Y566542D01*
X167100Y566500D01*
X166725Y566583D01*
X166433Y566750D01*
X166225Y567042D01*
X166183Y567375D01*
X166267Y567708D01*
X166475Y567917D01*
X166767Y568083D01*
X167058Y568125D01*
X167350Y568083D01*
X167725Y567917D01*
X167600Y569000D01*
X166475D01*
G01X164792Y567542D02*
X164500Y567833D01*
X164250Y568000D01*
X163917Y568083D01*
X163625Y568000D01*
X163417Y567833D01*
X163250Y567583D01*
X163208Y567292D01*
X163250Y567042D01*
X163417Y566792D01*
X163667Y566583D01*
X163958Y566500D01*
X164292Y566583D01*
X164583Y566833D01*
X164750Y567208D01*
X164792Y567625D01*
X164708Y568167D01*
X164583Y568458D01*
X164375Y568750D01*
X164083Y568958D01*
X163792Y569000D01*
X163500Y568917D01*
X163292Y568708D01*
G01X181236Y586598D02*
X181361Y586348D01*
X181444Y586056D01*
Y585723D01*
X181319Y585348D01*
X181111Y585056D01*
X180861Y584848D01*
X180444Y584681D01*
X180069Y584639D01*
X179694Y584723D01*
X179444Y584848D01*
X179194Y585098D01*
X179027Y585389D01*
X178944Y585681D01*
Y585973D01*
X179027Y586264D01*
X179152Y586514D01*
X179319Y586723D01*
G01X178944Y588781D02*
X181444D01*
X180944Y588281D01*
G01X178944D02*
Y589281D01*
G01X181444Y591881D02*
X181361Y591548D01*
X181152Y591298D01*
X180902Y591131D01*
X180569Y591006D01*
X180194Y590964D01*
X179819Y591006D01*
X179486Y591131D01*
X179236Y591298D01*
X179027Y591548D01*
X178944Y591881D01*
X179027Y592214D01*
X179236Y592464D01*
X179486Y592631D01*
X179819Y592756D01*
X180194Y592798D01*
X180569Y592756D01*
X180902Y592631D01*
X181152Y592464D01*
X181361Y592214D01*
X181444Y591881D01*
G01X178944Y594981D02*
X178986Y595273D01*
X179111Y595606D01*
X179319Y595814D01*
X179611Y595898D01*
X179902Y595814D01*
X180152Y595564D01*
X180277Y595189D01*
Y594773D01*
X180361Y594523D01*
X180569Y594314D01*
X180861Y594231D01*
X181152Y594356D01*
X181361Y594648D01*
X181444Y594981D01*
X181361Y595314D01*
X181152Y595606D01*
X180861Y595731D01*
X180569Y595648D01*
X180361Y595439D01*
X180277Y595189D01*
Y594773D01*
X180152Y594398D01*
X179902Y594148D01*
X179611Y594064D01*
X179319Y594148D01*
X179111Y594356D01*
X178986Y594689D01*
X178944Y594981D01*
G01X198233Y588792D02*
X198483Y588917D01*
X198775Y589000D01*
X199108D01*
X199483Y588875D01*
X199775Y588667D01*
X199983Y588417D01*
X200150Y588000D01*
X200192Y587625D01*
X200108Y587250D01*
X199983Y587000D01*
X199733Y586750D01*
X199442Y586583D01*
X199150Y586500D01*
X198858D01*
X198567Y586583D01*
X198317Y586708D01*
X198108Y586875D01*
G01X196050Y586500D02*
Y589000D01*
X196550Y588500D01*
G01Y586500D02*
X195550D01*
G01X192950Y589000D02*
X193283Y588917D01*
X193533Y588708D01*
X193700Y588458D01*
X193825Y588125D01*
X193867Y587750D01*
X193825Y587375D01*
X193700Y587042D01*
X193533Y586792D01*
X193283Y586583D01*
X192950Y586500D01*
X192617Y586583D01*
X192367Y586792D01*
X192200Y587042D01*
X192075Y587375D01*
X192033Y587750D01*
X192075Y588125D01*
X192200Y588458D01*
X192367Y588708D01*
X192617Y588917D01*
X192950Y589000D01*
G01X189933Y586500D02*
X189850Y587042D01*
X189725Y587500D01*
X189558Y587917D01*
X189350Y588375D01*
X189017Y589000D01*
X190683D01*
G01X212263Y589899D02*
X212513Y590024D01*
X212805Y590107D01*
X213138D01*
X213513Y589982D01*
X213805Y589774D01*
X214013Y589524D01*
X214180Y589107D01*
X214222Y588732D01*
X214138Y588357D01*
X214013Y588107D01*
X213763Y587857D01*
X213472Y587690D01*
X213180Y587607D01*
X212888D01*
X212597Y587690D01*
X212347Y587815D01*
X212138Y587982D01*
G01X210080Y587607D02*
Y590107D01*
X210580Y589607D01*
G01Y587607D02*
X209580D01*
G01X206980Y590107D02*
X207313Y590024D01*
X207563Y589815D01*
X207730Y589565D01*
X207855Y589232D01*
X207897Y588857D01*
X207855Y588482D01*
X207730Y588149D01*
X207563Y587899D01*
X207313Y587690D01*
X206980Y587607D01*
X206647Y587690D01*
X206397Y587899D01*
X206230Y588149D01*
X206105Y588482D01*
X206063Y588857D01*
X206105Y589232D01*
X206230Y589565D01*
X206397Y589815D01*
X206647Y590024D01*
X206980Y590107D01*
G01X203880Y587607D02*
Y590107D01*
X204380Y589607D01*
G01Y587607D02*
X203380D01*
G01X215524Y652295D02*
X215774Y652420D01*
X216066Y652503D01*
X216399D01*
X216774Y652378D01*
X217066Y652170D01*
X217274Y651920D01*
X217441Y651503D01*
X217483Y651128D01*
X217399Y650753D01*
X217274Y650503D01*
X217024Y650253D01*
X216733Y650086D01*
X216441Y650003D01*
X216149D01*
X215858Y650086D01*
X215608Y650211D01*
X215399Y650378D01*
G01X214133Y651045D02*
X213841Y651336D01*
X213591Y651503D01*
X213258Y651586D01*
X212966Y651503D01*
X212758Y651336D01*
X212591Y651086D01*
X212549Y650795D01*
X212591Y650545D01*
X212758Y650295D01*
X213008Y650086D01*
X213299Y650003D01*
X213633Y650086D01*
X213924Y650336D01*
X214091Y650711D01*
X214133Y651128D01*
X214049Y651670D01*
X213924Y651961D01*
X213716Y652253D01*
X213424Y652461D01*
X213133Y652503D01*
X212841Y652420D01*
X212633Y652211D01*
G01X211033Y652086D02*
X210783Y652336D01*
X210491Y652461D01*
X210158Y652503D01*
X209741Y652420D01*
X209449Y652211D01*
X209366Y651961D01*
X209408Y651711D01*
X209574Y651503D01*
X210408Y651086D01*
X210783Y650795D01*
X211033Y650378D01*
X211116Y650003D01*
X209366D01*
G01X207224D02*
X207141Y650545D01*
X207016Y651003D01*
X206849Y651420D01*
X206641Y651878D01*
X206308Y652503D01*
X207974D01*
G01X217274Y658003D02*
Y660503D01*
X216233D01*
X215899Y660378D01*
X215691Y660211D01*
X215608Y659878D01*
X215691Y659545D01*
X215941Y659336D01*
X216233Y659211D01*
X217274D01*
G01X216233D02*
X215608Y658003D01*
G01X213341D02*
X213049Y658045D01*
X212716Y658170D01*
X212508Y658378D01*
X212424Y658670D01*
X212508Y658961D01*
X212758Y659211D01*
X213133Y659336D01*
X213549D01*
X213799Y659420D01*
X214008Y659628D01*
X214091Y659920D01*
X213966Y660211D01*
X213674Y660420D01*
X213341Y660503D01*
X213008Y660420D01*
X212716Y660211D01*
X212591Y659920D01*
X212674Y659628D01*
X212883Y659420D01*
X213133Y659336D01*
X213549D01*
X213924Y659211D01*
X214174Y658961D01*
X214258Y658670D01*
X214174Y658378D01*
X213966Y658170D01*
X213633Y658045D01*
X213341Y658003D01*
G01X210241D02*
Y660503D01*
X210741Y660003D01*
G01Y658003D02*
X209741D01*
G01X207849Y658295D02*
X207558Y658086D01*
X207224Y658003D01*
X206891Y658086D01*
X206599Y658336D01*
X206391Y658711D01*
X206308Y659086D01*
Y659545D01*
X206391Y659920D01*
X206599Y660253D01*
X206849Y660420D01*
X207141Y660503D01*
X207474Y660420D01*
X207724Y660253D01*
X207891Y660003D01*
X207974Y659670D01*
X207891Y659378D01*
X207683Y659086D01*
X207433Y658920D01*
X207141Y658878D01*
X206808Y658961D01*
X206558Y659170D01*
X206308Y659545D01*
G01X201600Y640300D02*
Y644300D01*
X209000D01*
G01X217100Y644200D02*
Y640200D01*
X209700D01*
G01X190484Y657592D02*
Y660092D01*
X189443D01*
X189109Y659967D01*
X188901Y659800D01*
X188818Y659467D01*
X188901Y659134D01*
X189151Y658925D01*
X189443Y658800D01*
X190484D01*
G01X189443D02*
X188818Y657592D01*
G01X186551D02*
Y660092D01*
X187051Y659592D01*
G01Y657592D02*
X186051D01*
G01X184159Y657884D02*
X183868Y657675D01*
X183534Y657592D01*
X183201Y657675D01*
X182909Y657925D01*
X182701Y658300D01*
X182618Y658675D01*
Y659134D01*
X182701Y659509D01*
X182909Y659842D01*
X183159Y660009D01*
X183451Y660092D01*
X183784Y660009D01*
X184034Y659842D01*
X184201Y659592D01*
X184284Y659259D01*
X184201Y658967D01*
X183993Y658675D01*
X183743Y658509D01*
X183451Y658467D01*
X183118Y658550D01*
X182868Y658759D01*
X182618Y659134D01*
G01X181143Y659675D02*
X180893Y659925D01*
X180601Y660050D01*
X180268Y660092D01*
X179851Y660009D01*
X179559Y659800D01*
X179476Y659550D01*
X179518Y659300D01*
X179684Y659092D01*
X180518Y658675D01*
X180893Y658384D01*
X181143Y657967D01*
X181226Y657592D01*
X179476D01*
G01X185845Y640681D02*
Y644681D01*
X193245D01*
G01X203904Y657919D02*
Y660419D01*
X202863D01*
X202529Y660294D01*
X202321Y660127D01*
X202238Y659794D01*
X202321Y659461D01*
X202571Y659252D01*
X202863Y659127D01*
X203904D01*
G01X202863D02*
X202238Y657919D01*
G01X199971D02*
Y660419D01*
X200471Y659919D01*
G01Y657919D02*
X199471D01*
G01X197579Y658211D02*
X197288Y658002D01*
X196954Y657919D01*
X196621Y658002D01*
X196329Y658252D01*
X196121Y658627D01*
X196038Y659002D01*
Y659461D01*
X196121Y659836D01*
X196329Y660169D01*
X196579Y660336D01*
X196871Y660419D01*
X197204Y660336D01*
X197454Y660169D01*
X197621Y659919D01*
X197704Y659586D01*
X197621Y659294D01*
X197413Y659002D01*
X197163Y658836D01*
X196871Y658794D01*
X196538Y658877D01*
X196288Y659086D01*
X196038Y659461D01*
G01X193771Y657919D02*
Y660419D01*
X194271Y659919D01*
G01Y657919D02*
X193271D01*
G01X193700Y640800D02*
Y644800D01*
X201100D01*
G01X203904Y649919D02*
Y652419D01*
X202863D01*
X202529Y652294D01*
X202321Y652127D01*
X202238Y651794D01*
X202321Y651461D01*
X202571Y651252D01*
X202863Y651127D01*
X203904D01*
G01X202863D02*
X202238Y649919D01*
G01X199471D02*
Y652419D01*
X201013Y650627D01*
X198929D01*
G01X196871Y652419D02*
X197204Y652336D01*
X197454Y652127D01*
X197621Y651877D01*
X197746Y651544D01*
X197788Y651169D01*
X197746Y650794D01*
X197621Y650461D01*
X197454Y650211D01*
X197204Y650002D01*
X196871Y649919D01*
X196538Y650002D01*
X196288Y650211D01*
X196121Y650461D01*
X195996Y650794D01*
X195954Y651169D01*
X195996Y651544D01*
X196121Y651877D01*
X196288Y652127D01*
X196538Y652336D01*
X196871Y652419D01*
G01X193771D02*
X194104Y652336D01*
X194354Y652127D01*
X194521Y651877D01*
X194646Y651544D01*
X194688Y651169D01*
X194646Y650794D01*
X194521Y650461D01*
X194354Y650211D01*
X194104Y650002D01*
X193771Y649919D01*
X193438Y650002D01*
X193188Y650211D01*
X193021Y650461D01*
X192896Y650794D01*
X192854Y651169D01*
X192896Y651544D01*
X193021Y651877D01*
X193188Y652127D01*
X193438Y652336D01*
X193771Y652419D01*
G01X190454Y649754D02*
Y652254D01*
X189413D01*
X189079Y652129D01*
X188871Y651962D01*
X188788Y651629D01*
X188871Y651296D01*
X189121Y651087D01*
X189413Y650962D01*
X190454D01*
G01X189413D02*
X188788Y649754D01*
G01X187313Y651837D02*
X187063Y652087D01*
X186771Y652212D01*
X186438Y652254D01*
X186021Y652171D01*
X185729Y651962D01*
X185646Y651712D01*
X185688Y651462D01*
X185854Y651254D01*
X186688Y650837D01*
X187063Y650546D01*
X187313Y650129D01*
X187396Y649754D01*
X185646D01*
G01X184129Y650046D02*
X183838Y649837D01*
X183504Y649754D01*
X183171Y649837D01*
X182879Y650087D01*
X182671Y650462D01*
X182588Y650837D01*
Y651296D01*
X182671Y651671D01*
X182879Y652004D01*
X183129Y652171D01*
X183421Y652254D01*
X183754Y652171D01*
X184004Y652004D01*
X184171Y651754D01*
X184254Y651421D01*
X184171Y651129D01*
X183963Y650837D01*
X183713Y650671D01*
X183421Y650629D01*
X183088Y650712D01*
X182838Y650921D01*
X182588Y651296D01*
G01X180404Y649754D02*
X180321Y650296D01*
X180196Y650754D01*
X180029Y651171D01*
X179821Y651629D01*
X179488Y652254D01*
X181154D01*
G01X217274Y654003D02*
Y656503D01*
X216233D01*
X215899Y656378D01*
X215691Y656211D01*
X215608Y655878D01*
X215691Y655545D01*
X215941Y655336D01*
X216233Y655211D01*
X217274D01*
G01X216233D02*
X215608Y654003D01*
G01X213341D02*
X213049Y654045D01*
X212716Y654170D01*
X212508Y654378D01*
X212424Y654670D01*
X212508Y654961D01*
X212758Y655211D01*
X213133Y655336D01*
X213549D01*
X213799Y655420D01*
X214008Y655628D01*
X214091Y655920D01*
X213966Y656211D01*
X213674Y656420D01*
X213341Y656503D01*
X213008Y656420D01*
X212716Y656211D01*
X212591Y655920D01*
X212674Y655628D01*
X212883Y655420D01*
X213133Y655336D01*
X213549D01*
X213924Y655211D01*
X214174Y654961D01*
X214258Y654670D01*
X214174Y654378D01*
X213966Y654170D01*
X213633Y654045D01*
X213341Y654003D01*
G01X211033Y656086D02*
X210783Y656336D01*
X210491Y656461D01*
X210158Y656503D01*
X209741Y656420D01*
X209449Y656211D01*
X209366Y655961D01*
X209408Y655711D01*
X209574Y655503D01*
X210408Y655086D01*
X210783Y654795D01*
X211033Y654378D01*
X211116Y654003D01*
X209366D01*
G01X207141D02*
Y656503D01*
X207641Y656003D01*
G01Y654003D02*
X206641D01*
G01X190554Y653754D02*
Y656254D01*
X189513D01*
X189179Y656129D01*
X188971Y655962D01*
X188888Y655629D01*
X188971Y655296D01*
X189221Y655087D01*
X189513Y654962D01*
X190554D01*
G01X189513D02*
X188888Y653754D01*
G01X187413Y655837D02*
X187163Y656087D01*
X186871Y656212D01*
X186538Y656254D01*
X186121Y656171D01*
X185829Y655962D01*
X185746Y655712D01*
X185788Y655462D01*
X185954Y655254D01*
X186788Y654837D01*
X187163Y654546D01*
X187413Y654129D01*
X187496Y653754D01*
X185746D01*
G01X183521D02*
X183229Y653796D01*
X182896Y653921D01*
X182688Y654129D01*
X182604Y654421D01*
X182688Y654712D01*
X182938Y654962D01*
X183313Y655087D01*
X183729D01*
X183979Y655171D01*
X184188Y655379D01*
X184271Y655671D01*
X184146Y655962D01*
X183854Y656171D01*
X183521Y656254D01*
X183188Y656171D01*
X182896Y655962D01*
X182771Y655671D01*
X182854Y655379D01*
X183063Y655171D01*
X183313Y655087D01*
X183729D01*
X184104Y654962D01*
X184354Y654712D01*
X184438Y654421D01*
X184354Y654129D01*
X184146Y653921D01*
X183813Y653796D01*
X183521Y653754D01*
G01X180421D02*
Y656254D01*
X180921Y655754D01*
G01Y653754D02*
X179921D01*
G01X203324Y653779D02*
Y656279D01*
X202283D01*
X201949Y656154D01*
X201741Y655987D01*
X201658Y655654D01*
X201741Y655321D01*
X201991Y655112D01*
X202283Y654987D01*
X203324D01*
G01X202283D02*
X201658Y653779D01*
G01X200183Y655862D02*
X199933Y656112D01*
X199641Y656237D01*
X199308Y656279D01*
X198891Y656196D01*
X198599Y655987D01*
X198516Y655737D01*
X198558Y655487D01*
X198724Y655279D01*
X199558Y654862D01*
X199933Y654571D01*
X200183Y654154D01*
X200266Y653779D01*
X198516D01*
G01X196374D02*
X196291Y654321D01*
X196166Y654779D01*
X195999Y655196D01*
X195791Y655654D01*
X195458Y656279D01*
X197124D01*
G01X193899Y654071D02*
X193608Y653862D01*
X193274Y653779D01*
X192941Y653862D01*
X192649Y654112D01*
X192441Y654487D01*
X192358Y654862D01*
Y655321D01*
X192441Y655696D01*
X192649Y656029D01*
X192899Y656196D01*
X193191Y656279D01*
X193524Y656196D01*
X193774Y656029D01*
X193941Y655779D01*
X194024Y655446D01*
X193941Y655154D01*
X193733Y654862D01*
X193483Y654696D01*
X193191Y654654D01*
X192858Y654737D01*
X192608Y654946D01*
X192358Y655321D01*
G01X156983Y638500D02*
Y641000D01*
X155942D01*
X155608Y640875D01*
X155400Y640708D01*
X155317Y640375D01*
X155400Y640042D01*
X155650Y639833D01*
X155942Y639708D01*
X156983D01*
G01X155942D02*
X155317Y638500D01*
G01X153133D02*
X153050Y639042D01*
X152925Y639500D01*
X152758Y639917D01*
X152550Y640375D01*
X152217Y641000D01*
X153883D01*
G01X149950D02*
X150283Y640917D01*
X150533Y640708D01*
X150700Y640458D01*
X150825Y640125D01*
X150867Y639750D01*
X150825Y639375D01*
X150700Y639042D01*
X150533Y638792D01*
X150283Y638583D01*
X149950Y638500D01*
X149617Y638583D01*
X149367Y638792D01*
X149200Y639042D01*
X149075Y639375D01*
X149033Y639750D01*
X149075Y640125D01*
X149200Y640458D01*
X149367Y640708D01*
X149617Y640917D01*
X149950Y641000D01*
G01X146850D02*
X147183Y640917D01*
X147433Y640708D01*
X147600Y640458D01*
X147725Y640125D01*
X147767Y639750D01*
X147725Y639375D01*
X147600Y639042D01*
X147433Y638792D01*
X147183Y638583D01*
X146850Y638500D01*
X146517Y638583D01*
X146267Y638792D01*
X146100Y639042D01*
X145975Y639375D01*
X145933Y639750D01*
X145975Y640125D01*
X146100Y640458D01*
X146267Y640708D01*
X146517Y640917D01*
X146850Y641000D01*
G01X161459Y728767D02*
X161584Y728517D01*
X161667Y728225D01*
Y727892D01*
X161542Y727517D01*
X161334Y727225D01*
X161084Y727017D01*
X160667Y726850D01*
X160292Y726808D01*
X159917Y726892D01*
X159667Y727017D01*
X159417Y727267D01*
X159250Y727558D01*
X159167Y727850D01*
Y728142D01*
X159250Y728433D01*
X159375Y728683D01*
X159542Y728892D01*
G01X159167Y730950D02*
X161667D01*
X161167Y730450D01*
G01X159167D02*
Y731450D01*
G01Y733967D02*
X159709Y734050D01*
X160167Y734175D01*
X160584Y734342D01*
X161042Y734550D01*
X161667Y734883D01*
Y733217D01*
G01X159167Y737150D02*
X159209Y737442D01*
X159334Y737775D01*
X159542Y737983D01*
X159834Y738067D01*
X160125Y737983D01*
X160375Y737733D01*
X160500Y737358D01*
Y736942D01*
X160584Y736692D01*
X160792Y736483D01*
X161084Y736400D01*
X161375Y736525D01*
X161584Y736817D01*
X161667Y737150D01*
X161584Y737483D01*
X161375Y737775D01*
X161084Y737900D01*
X160792Y737817D01*
X160584Y737608D01*
X160500Y737358D01*
Y736942D01*
X160375Y736567D01*
X160125Y736317D01*
X159834Y736233D01*
X159542Y736317D01*
X159334Y736525D01*
X159209Y736858D01*
X159167Y737150D01*
G01X147667Y729017D02*
X150167D01*
Y730058D01*
X150042Y730392D01*
X149875Y730600D01*
X149542Y730683D01*
X149209Y730600D01*
X149000Y730350D01*
X148875Y730058D01*
Y729017D01*
G01Y730058D02*
X147667Y730683D01*
G01Y733450D02*
X150167D01*
X148375Y731908D01*
Y733992D01*
G01X147667Y736050D02*
X147709Y736342D01*
X147834Y736675D01*
X148042Y736883D01*
X148334Y736967D01*
X148625Y736883D01*
X148875Y736633D01*
X149000Y736258D01*
Y735842D01*
X149084Y735592D01*
X149292Y735383D01*
X149584Y735300D01*
X149875Y735425D01*
X150084Y735717D01*
X150167Y736050D01*
X150084Y736383D01*
X149875Y736675D01*
X149584Y736800D01*
X149292Y736717D01*
X149084Y736508D01*
X149000Y736258D01*
Y735842D01*
X148875Y735467D01*
X148625Y735217D01*
X148334Y735133D01*
X148042Y735217D01*
X147834Y735425D01*
X147709Y735758D01*
X147667Y736050D01*
G01Y739650D02*
X150167D01*
X148375Y738108D01*
Y740192D01*
G01X153200Y712500D02*
Y717700D01*
G01X146200Y712500D02*
Y720300D01*
G01X153200Y712500D02*
X146200D01*
G01X153200Y725900D02*
Y717200D01*
G01X146200Y725900D02*
X153200D01*
G01X146200Y719500D02*
Y725900D01*
G01X231163Y492319D02*
X231288Y492069D01*
X231371Y491777D01*
Y491444D01*
X231246Y491069D01*
X231038Y490777D01*
X230788Y490569D01*
X230371Y490402D01*
X229996Y490360D01*
X229621Y490444D01*
X229371Y490569D01*
X229121Y490819D01*
X228954Y491110D01*
X228871Y491402D01*
Y491694D01*
X228954Y491985D01*
X229079Y492235D01*
X229246Y492444D01*
G01Y493585D02*
X229038Y493835D01*
X228913Y494127D01*
X228871Y494502D01*
X228954Y494877D01*
X229121Y495169D01*
X229413Y495377D01*
X229746Y495419D01*
X230079Y495335D01*
X230288Y495127D01*
X230454Y494835D01*
X230496Y494544D01*
X230454Y494252D01*
X230288Y493877D01*
X231371Y494002D01*
Y495127D01*
G01Y497602D02*
X231288Y497269D01*
X231079Y497019D01*
X230829Y496852D01*
X230496Y496727D01*
X230121Y496685D01*
X229746Y496727D01*
X229413Y496852D01*
X229163Y497019D01*
X228954Y497269D01*
X228871Y497602D01*
X228954Y497935D01*
X229163Y498185D01*
X229413Y498352D01*
X229746Y498477D01*
X230121Y498519D01*
X230496Y498477D01*
X230829Y498352D01*
X231079Y498185D01*
X231288Y497935D01*
X231371Y497602D01*
G01X229246Y499785D02*
X229038Y500035D01*
X228913Y500327D01*
X228871Y500702D01*
X228954Y501077D01*
X229121Y501369D01*
X229413Y501577D01*
X229746Y501619D01*
X230079Y501535D01*
X230288Y501327D01*
X230454Y501035D01*
X230496Y500744D01*
X230454Y500452D01*
X230288Y500077D01*
X231371Y500202D01*
Y501327D01*
G01X224250Y456763D02*
X224500Y456888D01*
X224792Y456971D01*
X225125D01*
X225500Y456846D01*
X225792Y456638D01*
X226000Y456388D01*
X226167Y455971D01*
X226209Y455596D01*
X226125Y455221D01*
X226000Y454971D01*
X225750Y454721D01*
X225459Y454554D01*
X225167Y454471D01*
X224875D01*
X224584Y454554D01*
X224334Y454679D01*
X224125Y454846D01*
G01X222984D02*
X222734Y454638D01*
X222442Y454513D01*
X222067Y454471D01*
X221692Y454554D01*
X221400Y454721D01*
X221192Y455013D01*
X221150Y455346D01*
X221234Y455679D01*
X221442Y455888D01*
X221734Y456054D01*
X222025Y456096D01*
X222317Y456054D01*
X222692Y455888D01*
X222567Y456971D01*
X221442D01*
G01X218967D02*
X219300Y456888D01*
X219550Y456679D01*
X219717Y456429D01*
X219842Y456096D01*
X219884Y455721D01*
X219842Y455346D01*
X219717Y455013D01*
X219550Y454763D01*
X219300Y454554D01*
X218967Y454471D01*
X218634Y454554D01*
X218384Y454763D01*
X218217Y455013D01*
X218092Y455346D01*
X218050Y455721D01*
X218092Y456096D01*
X218217Y456429D01*
X218384Y456679D01*
X218634Y456888D01*
X218967Y456971D01*
G01X216659Y455513D02*
X216367Y455804D01*
X216117Y455971D01*
X215784Y456054D01*
X215492Y455971D01*
X215284Y455804D01*
X215117Y455554D01*
X215075Y455263D01*
X215117Y455013D01*
X215284Y454763D01*
X215534Y454554D01*
X215825Y454471D01*
X216159Y454554D01*
X216450Y454804D01*
X216617Y455179D01*
X216659Y455596D01*
X216575Y456138D01*
X216450Y456429D01*
X216242Y456721D01*
X215950Y456929D01*
X215659Y456971D01*
X215367Y456888D01*
X215159Y456679D01*
G01X235194Y472092D02*
X237694D01*
Y473133D01*
X237569Y473467D01*
X237402Y473675D01*
X237069Y473758D01*
X236736Y473675D01*
X236527Y473425D01*
X236402Y473133D01*
Y472092D01*
G01Y473133D02*
X235194Y473758D01*
G01X235694Y475108D02*
X235402Y475358D01*
X235236Y475692D01*
X235194Y476067D01*
X235236Y476400D01*
X235444Y476733D01*
X235694Y476942D01*
X235944Y476983D01*
X236236Y476900D01*
X236444Y476608D01*
X236527Y476317D01*
Y475942D01*
G01Y476317D02*
X236652Y476567D01*
X236861Y476775D01*
X237111Y476858D01*
X237361Y476775D01*
X237569Y476567D01*
X237694Y476192D01*
X237652Y475817D01*
X237486Y475442D01*
G01X235194Y479625D02*
X237694D01*
X235902Y478083D01*
Y480167D01*
G01X235194Y482142D02*
X235736Y482225D01*
X236194Y482350D01*
X236611Y482517D01*
X237069Y482725D01*
X237694Y483058D01*
Y481392D01*
G01X239730Y464761D02*
X242230D01*
Y465802D01*
X242105Y466136D01*
X241938Y466344D01*
X241605Y466427D01*
X241272Y466344D01*
X241063Y466094D01*
X240938Y465802D01*
Y464761D01*
G01Y465802D02*
X239730Y466427D01*
G01X240230Y467777D02*
X239938Y468027D01*
X239772Y468361D01*
X239730Y468736D01*
X239772Y469069D01*
X239980Y469402D01*
X240230Y469611D01*
X240480Y469652D01*
X240772Y469569D01*
X240980Y469277D01*
X241063Y468986D01*
Y468611D01*
G01Y468986D02*
X241188Y469236D01*
X241397Y469444D01*
X241647Y469527D01*
X241897Y469444D01*
X242105Y469236D01*
X242230Y468861D01*
X242188Y468486D01*
X242022Y468111D01*
G01X240230Y470877D02*
X239938Y471127D01*
X239772Y471461D01*
X239730Y471836D01*
X239772Y472169D01*
X239980Y472502D01*
X240230Y472711D01*
X240480Y472752D01*
X240772Y472669D01*
X240980Y472377D01*
X241063Y472086D01*
Y471711D01*
G01Y472086D02*
X241188Y472336D01*
X241397Y472544D01*
X241647Y472627D01*
X241897Y472544D01*
X242105Y472336D01*
X242230Y471961D01*
X242188Y471586D01*
X242022Y471211D01*
G01X240022Y474186D02*
X239813Y474477D01*
X239730Y474811D01*
X239813Y475144D01*
X240063Y475436D01*
X240438Y475644D01*
X240813Y475727D01*
X241272D01*
X241647Y475644D01*
X241980Y475436D01*
X242147Y475186D01*
X242230Y474894D01*
X242147Y474561D01*
X241980Y474311D01*
X241730Y474144D01*
X241397Y474061D01*
X241105Y474144D01*
X240813Y474352D01*
X240647Y474602D01*
X240605Y474894D01*
X240688Y475227D01*
X240897Y475477D01*
X241272Y475727D01*
G01X215908Y485035D02*
X219908D01*
Y477635D01*
G01X226100Y458471D02*
Y460971D01*
X225059D01*
X224725Y460846D01*
X224517Y460679D01*
X224434Y460346D01*
X224517Y460013D01*
X224767Y459804D01*
X225059Y459679D01*
X226100D01*
G01X225059D02*
X224434Y458471D01*
G01X223084Y458971D02*
X222834Y458679D01*
X222500Y458513D01*
X222125Y458471D01*
X221792Y458513D01*
X221459Y458721D01*
X221250Y458971D01*
X221209Y459221D01*
X221292Y459513D01*
X221584Y459721D01*
X221875Y459804D01*
X222250D01*
G01X221875D02*
X221625Y459929D01*
X221417Y460138D01*
X221334Y460388D01*
X221417Y460638D01*
X221625Y460846D01*
X222000Y460971D01*
X222375Y460929D01*
X222750Y460763D01*
G01X219984Y458971D02*
X219734Y458679D01*
X219400Y458513D01*
X219025Y458471D01*
X218692Y458513D01*
X218359Y458721D01*
X218150Y458971D01*
X218109Y459221D01*
X218192Y459513D01*
X218484Y459721D01*
X218775Y459804D01*
X219150D01*
G01X218775D02*
X218525Y459929D01*
X218317Y460138D01*
X218234Y460388D01*
X218317Y460638D01*
X218525Y460846D01*
X218900Y460971D01*
X219275Y460929D01*
X219650Y460763D01*
G01X216050Y458471D02*
X215967Y459013D01*
X215842Y459471D01*
X215675Y459888D01*
X215467Y460346D01*
X215134Y460971D01*
X216800D01*
G01X214300Y469100D02*
Y473100D01*
X221700D01*
G01X225571Y463100D02*
X228071D01*
Y464141D01*
X227946Y464475D01*
X227779Y464683D01*
X227446Y464766D01*
X227113Y464683D01*
X226904Y464433D01*
X226779Y464141D01*
Y463100D01*
G01Y464141D02*
X225571Y464766D01*
G01X227654Y466241D02*
X227904Y466491D01*
X228029Y466783D01*
X228071Y467116D01*
X227988Y467533D01*
X227779Y467825D01*
X227529Y467908D01*
X227279Y467866D01*
X227071Y467700D01*
X226654Y466866D01*
X226363Y466491D01*
X225946Y466241D01*
X225571Y466158D01*
Y467908D01*
G01Y470133D02*
X225613Y470425D01*
X225738Y470758D01*
X225946Y470966D01*
X226238Y471050D01*
X226529Y470966D01*
X226779Y470716D01*
X226904Y470341D01*
Y469925D01*
X226988Y469675D01*
X227196Y469466D01*
X227488Y469383D01*
X227779Y469508D01*
X227988Y469800D01*
X228071Y470133D01*
X227988Y470466D01*
X227779Y470758D01*
X227488Y470883D01*
X227196Y470800D01*
X226988Y470591D01*
X226904Y470341D01*
Y469925D01*
X226779Y469550D01*
X226529Y469300D01*
X226238Y469216D01*
X225946Y469300D01*
X225738Y469508D01*
X225613Y469841D01*
X225571Y470133D01*
G01X225946Y472316D02*
X225738Y472566D01*
X225613Y472858D01*
X225571Y473233D01*
X225654Y473608D01*
X225821Y473900D01*
X226113Y474108D01*
X226446Y474150D01*
X226779Y474066D01*
X226988Y473858D01*
X227154Y473566D01*
X227196Y473275D01*
X227154Y472983D01*
X226988Y472608D01*
X228071Y472733D01*
Y473858D01*
G01X220100Y480600D02*
X224100D01*
Y473200D01*
G01X239456Y478698D02*
X241956D01*
Y479739D01*
X241831Y480073D01*
X241664Y480281D01*
X241331Y480364D01*
X240998Y480281D01*
X240789Y480031D01*
X240664Y479739D01*
Y478698D01*
G01Y479739D02*
X239456Y480364D01*
G01Y482548D02*
X239998Y482631D01*
X240456Y482756D01*
X240873Y482923D01*
X241331Y483131D01*
X241956Y483464D01*
Y481798D01*
G01Y485731D02*
X241873Y485398D01*
X241664Y485148D01*
X241414Y484981D01*
X241081Y484856D01*
X240706Y484814D01*
X240331Y484856D01*
X239998Y484981D01*
X239748Y485148D01*
X239539Y485398D01*
X239456Y485731D01*
X239539Y486064D01*
X239748Y486314D01*
X239998Y486481D01*
X240331Y486606D01*
X240706Y486648D01*
X241081Y486606D01*
X241414Y486481D01*
X241664Y486314D01*
X241873Y486064D01*
X241956Y485731D01*
G01X241539Y488039D02*
X241789Y488289D01*
X241914Y488581D01*
X241956Y488914D01*
X241873Y489331D01*
X241664Y489623D01*
X241414Y489706D01*
X241164Y489664D01*
X240956Y489498D01*
X240539Y488664D01*
X240248Y488289D01*
X239831Y488039D01*
X239456Y487956D01*
Y489706D01*
G01X220500Y485300D02*
X216500D01*
Y492700D01*
G01X257325Y475430D02*
Y477930D01*
X256284D01*
X255950Y477805D01*
X255742Y477638D01*
X255659Y477305D01*
X255742Y476972D01*
X255992Y476763D01*
X256284Y476638D01*
X257325D01*
G01X256284D02*
X255659Y475430D01*
G01X254309Y475930D02*
X254059Y475638D01*
X253725Y475472D01*
X253350Y475430D01*
X253017Y475472D01*
X252684Y475680D01*
X252475Y475930D01*
X252434Y476180D01*
X252517Y476472D01*
X252809Y476680D01*
X253100Y476763D01*
X253475D01*
G01X253100D02*
X252850Y476888D01*
X252642Y477097D01*
X252559Y477347D01*
X252642Y477597D01*
X252850Y477805D01*
X253225Y477930D01*
X253600Y477888D01*
X253975Y477722D01*
G01X249792Y475430D02*
Y477930D01*
X251334Y476138D01*
X249250D01*
G01X248109Y475805D02*
X247859Y475597D01*
X247567Y475472D01*
X247192Y475430D01*
X246817Y475513D01*
X246525Y475680D01*
X246317Y475972D01*
X246275Y476305D01*
X246359Y476638D01*
X246567Y476847D01*
X246859Y477013D01*
X247150Y477055D01*
X247442Y477013D01*
X247817Y476847D01*
X247692Y477930D01*
X246567D01*
G01X223025Y482151D02*
Y486151D01*
X230425D01*
G01X236993Y491835D02*
X235201D01*
X234826Y492002D01*
X234576Y492335D01*
X234493Y492752D01*
X234576Y493169D01*
X234826Y493502D01*
X235201Y493669D01*
X236993D01*
G01X234993Y494935D02*
X234701Y495185D01*
X234535Y495519D01*
X234493Y495894D01*
X234535Y496227D01*
X234743Y496560D01*
X234993Y496769D01*
X235243Y496810D01*
X235535Y496727D01*
X235743Y496435D01*
X235826Y496144D01*
Y495769D01*
G01Y496144D02*
X235951Y496394D01*
X236160Y496602D01*
X236410Y496685D01*
X236660Y496602D01*
X236868Y496394D01*
X236993Y496019D01*
X236951Y495644D01*
X236785Y495269D01*
G01X234493Y498869D02*
X235035Y498952D01*
X235493Y499077D01*
X235910Y499244D01*
X236368Y499452D01*
X236993Y499785D01*
Y498119D01*
G01X233142Y550387D02*
X229809Y557387D01*
X226476Y550387D01*
G01X227676Y552837D02*
X231942D01*
G01X217500Y550700D02*
Y543000D01*
X223000D01*
Y542000D01*
G01X227400Y540000D02*
X256509D01*
X256510Y540001D01*
G01X257192Y507567D02*
X257317Y507317D01*
X257400Y507025D01*
Y506692D01*
X257275Y506317D01*
X257067Y506025D01*
X256817Y505817D01*
X256400Y505650D01*
X256025Y505608D01*
X255650Y505692D01*
X255400Y505817D01*
X255150Y506067D01*
X254983Y506358D01*
X254900Y506650D01*
Y506942D01*
X254983Y507233D01*
X255108Y507483D01*
X255275Y507692D01*
G01X254900Y509750D02*
X257400D01*
X256900Y509250D01*
G01X254900D02*
Y510250D01*
G01Y512850D02*
X257400D01*
X256900Y512350D01*
G01X254900D02*
Y513350D01*
G01X255942Y515158D02*
X256233Y515450D01*
X256400Y515700D01*
X256483Y516033D01*
X256400Y516325D01*
X256233Y516533D01*
X255983Y516700D01*
X255692Y516742D01*
X255442Y516700D01*
X255192Y516533D01*
X254983Y516283D01*
X254900Y515992D01*
X254983Y515658D01*
X255233Y515367D01*
X255608Y515200D01*
X256025Y515158D01*
X256567Y515242D01*
X256858Y515367D01*
X257150Y515575D01*
X257358Y515867D01*
X257400Y516158D01*
X257317Y516450D01*
X257108Y516658D01*
G01X252500Y520217D02*
X255000D01*
Y521258D01*
X254875Y521592D01*
X254708Y521800D01*
X254375Y521883D01*
X254042Y521800D01*
X253833Y521550D01*
X253708Y521258D01*
Y520217D01*
G01Y521258D02*
X252500Y521883D01*
G01Y524150D02*
X255000D01*
X254500Y523650D01*
G01X252500D02*
Y524650D01*
G01Y527750D02*
X255000D01*
X253208Y526208D01*
Y528292D01*
G01X254583Y529558D02*
X254833Y529808D01*
X254958Y530100D01*
X255000Y530433D01*
X254917Y530850D01*
X254708Y531142D01*
X254458Y531225D01*
X254208Y531183D01*
X254000Y531017D01*
X253583Y530183D01*
X253292Y529808D01*
X252875Y529558D01*
X252500Y529475D01*
Y531225D01*
G01X231300Y549100D02*
X235300D01*
Y541700D01*
G01Y549100D02*
X239300D01*
Y541700D01*
G01X247500Y565100D02*
Y569100D01*
X254900D01*
G01X244980Y563968D02*
X248980D01*
Y556568D01*
G01X280900Y554017D02*
X283400D01*
Y555058D01*
X283275Y555392D01*
X283108Y555600D01*
X282775Y555683D01*
X282442Y555600D01*
X282233Y555350D01*
X282108Y555058D01*
Y554017D01*
G01Y555058D02*
X280900Y555683D01*
G01Y557950D02*
X283400D01*
X282900Y557450D01*
G01X280900D02*
Y558450D01*
G01X281192Y560342D02*
X280983Y560633D01*
X280900Y560967D01*
X280983Y561300D01*
X281233Y561592D01*
X281608Y561800D01*
X281983Y561883D01*
X282442D01*
X282817Y561800D01*
X283150Y561592D01*
X283317Y561342D01*
X283400Y561050D01*
X283317Y560717D01*
X283150Y560467D01*
X282900Y560300D01*
X282567Y560217D01*
X282275Y560300D01*
X281983Y560508D01*
X281817Y560758D01*
X281775Y561050D01*
X281858Y561383D01*
X282067Y561633D01*
X282442Y561883D01*
G01X281400Y563233D02*
X281108Y563483D01*
X280942Y563817D01*
X280900Y564192D01*
X280942Y564525D01*
X281150Y564858D01*
X281400Y565067D01*
X281650Y565108D01*
X281942Y565025D01*
X282150Y564733D01*
X282233Y564442D01*
Y564067D01*
G01Y564442D02*
X282358Y564692D01*
X282567Y564900D01*
X282817Y564983D01*
X283067Y564900D01*
X283275Y564692D01*
X283400Y564317D01*
X283358Y563942D01*
X283192Y563567D01*
G01X275809Y558411D02*
X271809D01*
Y565811D01*
G01X247000Y541600D02*
Y545600D01*
X254400D01*
G01X246800Y545700D02*
Y541700D01*
X239400D01*
G01X268100Y519917D02*
X270600D01*
Y520958D01*
X270475Y521292D01*
X270308Y521500D01*
X269975Y521583D01*
X269642Y521500D01*
X269433Y521250D01*
X269308Y520958D01*
Y519917D01*
G01Y520958D02*
X268100Y521583D01*
G01X268600Y522933D02*
X268308Y523183D01*
X268142Y523517D01*
X268100Y523892D01*
X268142Y524225D01*
X268350Y524558D01*
X268600Y524767D01*
X268850Y524808D01*
X269142Y524725D01*
X269350Y524433D01*
X269433Y524142D01*
Y523767D01*
G01Y524142D02*
X269558Y524392D01*
X269767Y524600D01*
X270017Y524683D01*
X270267Y524600D01*
X270475Y524392D01*
X270600Y524017D01*
X270558Y523642D01*
X270392Y523267D01*
G01X268475Y526033D02*
X268267Y526283D01*
X268142Y526575D01*
X268100Y526950D01*
X268183Y527325D01*
X268350Y527617D01*
X268642Y527825D01*
X268975Y527867D01*
X269308Y527783D01*
X269517Y527575D01*
X269683Y527283D01*
X269725Y526992D01*
X269683Y526700D01*
X269517Y526325D01*
X270600Y526450D01*
Y527575D01*
G01X268475Y529133D02*
X268267Y529383D01*
X268142Y529675D01*
X268100Y530050D01*
X268183Y530425D01*
X268350Y530717D01*
X268642Y530925D01*
X268975Y530967D01*
X269308Y530883D01*
X269517Y530675D01*
X269683Y530383D01*
X269725Y530092D01*
X269683Y529800D01*
X269517Y529425D01*
X270600Y529550D01*
Y530675D01*
G01X271965Y519896D02*
X274465D01*
Y520937D01*
X274340Y521271D01*
X274173Y521479D01*
X273840Y521562D01*
X273507Y521479D01*
X273298Y521229D01*
X273173Y520937D01*
Y519896D01*
G01Y520937D02*
X271965Y521562D01*
G01X272465Y522912D02*
X272173Y523162D01*
X272007Y523496D01*
X271965Y523871D01*
X272007Y524204D01*
X272215Y524537D01*
X272465Y524746D01*
X272715Y524787D01*
X273007Y524704D01*
X273215Y524412D01*
X273298Y524121D01*
Y523746D01*
G01Y524121D02*
X273423Y524371D01*
X273632Y524579D01*
X273882Y524662D01*
X274132Y524579D01*
X274340Y524371D01*
X274465Y523996D01*
X274423Y523621D01*
X274257Y523246D01*
G01X272340Y526012D02*
X272132Y526262D01*
X272007Y526554D01*
X271965Y526929D01*
X272048Y527304D01*
X272215Y527596D01*
X272507Y527804D01*
X272840Y527846D01*
X273173Y527762D01*
X273382Y527554D01*
X273548Y527262D01*
X273590Y526971D01*
X273548Y526679D01*
X273382Y526304D01*
X274465Y526429D01*
Y527554D01*
G01X272465Y529112D02*
X272173Y529362D01*
X272007Y529696D01*
X271965Y530071D01*
X272007Y530404D01*
X272215Y530737D01*
X272465Y530946D01*
X272715Y530987D01*
X273007Y530904D01*
X273215Y530612D01*
X273298Y530321D01*
Y529946D01*
G01Y530321D02*
X273423Y530571D01*
X273632Y530779D01*
X273882Y530862D01*
X274132Y530779D01*
X274340Y530571D01*
X274465Y530196D01*
X274423Y529821D01*
X274257Y529446D01*
G01X217448Y530201D02*
X213448D01*
Y537601D01*
G01X250683Y530300D02*
Y532800D01*
X249642D01*
X249308Y532675D01*
X249100Y532508D01*
X249017Y532175D01*
X249100Y531842D01*
X249350Y531633D01*
X249642Y531508D01*
X250683D01*
G01X249642D02*
X249017Y530300D01*
G01X246750D02*
Y532800D01*
X247250Y532300D01*
G01Y530300D02*
X246250D01*
G01X243150D02*
Y532800D01*
X244692Y531008D01*
X242608D01*
G01X240550Y532800D02*
X240883Y532717D01*
X241133Y532508D01*
X241300Y532258D01*
X241425Y531925D01*
X241467Y531550D01*
X241425Y531175D01*
X241300Y530842D01*
X241133Y530592D01*
X240883Y530383D01*
X240550Y530300D01*
X240217Y530383D01*
X239967Y530592D01*
X239800Y530842D01*
X239675Y531175D01*
X239633Y531550D01*
X239675Y531925D01*
X239800Y532258D01*
X239967Y532508D01*
X240217Y532717D01*
X240550Y532800D01*
G01X233400Y569000D02*
Y565000D01*
X226000D01*
G01X291883Y528800D02*
Y531300D01*
X290842D01*
X290508Y531175D01*
X290300Y531008D01*
X290217Y530675D01*
X290300Y530342D01*
X290550Y530133D01*
X290842Y530008D01*
X291883D01*
G01X290842D02*
X290217Y528800D01*
G01X288742Y530883D02*
X288492Y531133D01*
X288200Y531258D01*
X287867Y531300D01*
X287450Y531217D01*
X287158Y531008D01*
X287075Y530758D01*
X287117Y530508D01*
X287283Y530300D01*
X288117Y529883D01*
X288492Y529592D01*
X288742Y529175D01*
X288825Y528800D01*
X287075D01*
G01X285558Y529092D02*
X285267Y528883D01*
X284933Y528800D01*
X284600Y528883D01*
X284308Y529133D01*
X284100Y529508D01*
X284017Y529883D01*
Y530342D01*
X284100Y530717D01*
X284308Y531050D01*
X284558Y531217D01*
X284850Y531300D01*
X285183Y531217D01*
X285433Y531050D01*
X285600Y530800D01*
X285683Y530467D01*
X285600Y530175D01*
X285392Y529883D01*
X285142Y529717D01*
X284850Y529675D01*
X284517Y529758D01*
X284267Y529967D01*
X284017Y530342D01*
G01X282667Y529175D02*
X282417Y528967D01*
X282125Y528842D01*
X281750Y528800D01*
X281375Y528883D01*
X281083Y529050D01*
X280875Y529342D01*
X280833Y529675D01*
X280917Y530008D01*
X281125Y530217D01*
X281417Y530383D01*
X281708Y530425D01*
X282000Y530383D01*
X282375Y530217D01*
X282250Y531300D01*
X281125D01*
G01X231757Y536556D02*
Y532556D01*
X224357D01*
G01X275500Y519917D02*
X278000D01*
Y520958D01*
X277875Y521292D01*
X277708Y521500D01*
X277375Y521583D01*
X277042Y521500D01*
X276833Y521250D01*
X276708Y520958D01*
Y519917D01*
G01Y520958D02*
X275500Y521583D01*
G01Y523850D02*
X278000D01*
X277500Y523350D01*
G01X275500D02*
Y524350D01*
G01X276542Y526158D02*
X276833Y526450D01*
X277000Y526700D01*
X277083Y527033D01*
X277000Y527325D01*
X276833Y527533D01*
X276583Y527700D01*
X276292Y527742D01*
X276042Y527700D01*
X275792Y527533D01*
X275583Y527283D01*
X275500Y526992D01*
X275583Y526658D01*
X275833Y526367D01*
X276208Y526200D01*
X276625Y526158D01*
X277167Y526242D01*
X277458Y526367D01*
X277750Y526575D01*
X277958Y526867D01*
X278000Y527158D01*
X277917Y527450D01*
X277708Y527658D01*
G01X275792Y529342D02*
X275583Y529633D01*
X275500Y529967D01*
X275583Y530300D01*
X275833Y530592D01*
X276208Y530800D01*
X276583Y530883D01*
X277042D01*
X277417Y530800D01*
X277750Y530592D01*
X277917Y530342D01*
X278000Y530050D01*
X277917Y529717D01*
X277750Y529467D01*
X277500Y529300D01*
X277167Y529217D01*
X276875Y529300D01*
X276583Y529508D01*
X276417Y529758D01*
X276375Y530050D01*
X276458Y530383D01*
X276667Y530633D01*
X277042Y530883D01*
G01X217473Y537573D02*
X221473D01*
Y530173D01*
G01X264400Y519917D02*
X266900D01*
Y520958D01*
X266775Y521292D01*
X266608Y521500D01*
X266275Y521583D01*
X265942Y521500D01*
X265733Y521250D01*
X265608Y520958D01*
Y519917D01*
G01Y520958D02*
X264400Y521583D01*
G01Y523850D02*
X266900D01*
X266400Y523350D01*
G01X264400D02*
Y524350D01*
G01X265442Y526158D02*
X265733Y526450D01*
X265900Y526700D01*
X265983Y527033D01*
X265900Y527325D01*
X265733Y527533D01*
X265483Y527700D01*
X265192Y527742D01*
X264942Y527700D01*
X264692Y527533D01*
X264483Y527283D01*
X264400Y526992D01*
X264483Y526658D01*
X264733Y526367D01*
X265108Y526200D01*
X265525Y526158D01*
X266067Y526242D01*
X266358Y526367D01*
X266650Y526575D01*
X266858Y526867D01*
X266900Y527158D01*
X266817Y527450D01*
X266608Y527658D01*
G01X264400Y529967D02*
X264942Y530050D01*
X265400Y530175D01*
X265817Y530342D01*
X266275Y530550D01*
X266900Y530883D01*
Y529217D01*
G01X264100Y557017D02*
X266600D01*
Y558058D01*
X266475Y558392D01*
X266308Y558600D01*
X265975Y558683D01*
X265642Y558600D01*
X265433Y558350D01*
X265308Y558058D01*
Y557017D01*
G01Y558058D02*
X264100Y558683D01*
G01Y560950D02*
X266600D01*
X266100Y560450D01*
G01X264100D02*
Y561450D01*
G01X264475Y563133D02*
X264267Y563383D01*
X264142Y563675D01*
X264100Y564050D01*
X264183Y564425D01*
X264350Y564717D01*
X264642Y564925D01*
X264975Y564967D01*
X265308Y564883D01*
X265517Y564675D01*
X265683Y564383D01*
X265725Y564092D01*
X265683Y563800D01*
X265517Y563425D01*
X266600Y563550D01*
Y564675D01*
G01X264392Y566442D02*
X264183Y566733D01*
X264100Y567067D01*
X264183Y567400D01*
X264433Y567692D01*
X264808Y567900D01*
X265183Y567983D01*
X265642D01*
X266017Y567900D01*
X266350Y567692D01*
X266517Y567442D01*
X266600Y567150D01*
X266517Y566817D01*
X266350Y566567D01*
X266100Y566400D01*
X265767Y566317D01*
X265475Y566400D01*
X265183Y566608D01*
X265017Y566858D01*
X264975Y567150D01*
X265058Y567483D01*
X265267Y567733D01*
X265642Y567983D01*
G01X271709Y558413D02*
X267709D01*
Y565813D01*
G01X238800Y518217D02*
X241300D01*
Y519258D01*
X241175Y519592D01*
X241008Y519800D01*
X240675Y519883D01*
X240342Y519800D01*
X240133Y519550D01*
X240008Y519258D01*
Y518217D01*
G01Y519258D02*
X238800Y519883D01*
G01Y522150D02*
X241300D01*
X240800Y521650D01*
G01X238800D02*
Y522650D01*
G01X239175Y524333D02*
X238967Y524583D01*
X238842Y524875D01*
X238800Y525250D01*
X238883Y525625D01*
X239050Y525917D01*
X239342Y526125D01*
X239675Y526167D01*
X240008Y526083D01*
X240217Y525875D01*
X240383Y525583D01*
X240425Y525292D01*
X240383Y525000D01*
X240217Y524625D01*
X241300Y524750D01*
Y525875D01*
G01X238800Y528850D02*
X241300D01*
X239508Y527308D01*
Y529392D01*
G01X239430Y564732D02*
Y568732D01*
X246830D01*
G01X242500Y518217D02*
X245000D01*
Y519258D01*
X244875Y519592D01*
X244708Y519800D01*
X244375Y519883D01*
X244042Y519800D01*
X243833Y519550D01*
X243708Y519258D01*
Y518217D01*
G01Y519258D02*
X242500Y519883D01*
G01Y522150D02*
X245000D01*
X244500Y521650D01*
G01X242500D02*
Y522650D01*
G01X242875Y524333D02*
X242667Y524583D01*
X242542Y524875D01*
X242500Y525250D01*
X242583Y525625D01*
X242750Y525917D01*
X243042Y526125D01*
X243375Y526167D01*
X243708Y526083D01*
X243917Y525875D01*
X244083Y525583D01*
X244125Y525292D01*
X244083Y525000D01*
X243917Y524625D01*
X245000Y524750D01*
Y525875D01*
G01X244583Y527558D02*
X244833Y527808D01*
X244958Y528100D01*
X245000Y528433D01*
X244917Y528850D01*
X244708Y529142D01*
X244458Y529225D01*
X244208Y529183D01*
X244000Y529017D01*
X243583Y528183D01*
X243292Y527808D01*
X242875Y527558D01*
X242500Y527475D01*
Y529225D01*
G01X237520Y560521D02*
Y564521D01*
X244920D01*
G01X256500Y520217D02*
X259000D01*
Y521258D01*
X258875Y521592D01*
X258708Y521800D01*
X258375Y521883D01*
X258042Y521800D01*
X257833Y521550D01*
X257708Y521258D01*
Y520217D01*
G01Y521258D02*
X256500Y521883D01*
G01X258583Y523358D02*
X258833Y523608D01*
X258958Y523900D01*
X259000Y524233D01*
X258917Y524650D01*
X258708Y524942D01*
X258458Y525025D01*
X258208Y524983D01*
X258000Y524817D01*
X257583Y523983D01*
X257292Y523608D01*
X256875Y523358D01*
X256500Y523275D01*
Y525025D01*
G01X256792Y526542D02*
X256583Y526833D01*
X256500Y527167D01*
X256583Y527500D01*
X256833Y527792D01*
X257208Y528000D01*
X257583Y528083D01*
X258042D01*
X258417Y528000D01*
X258750Y527792D01*
X258917Y527542D01*
X259000Y527250D01*
X258917Y526917D01*
X258750Y526667D01*
X258500Y526500D01*
X258167Y526417D01*
X257875Y526500D01*
X257583Y526708D01*
X257417Y526958D01*
X257375Y527250D01*
X257458Y527583D01*
X257667Y527833D01*
X258042Y528083D01*
G01X256500Y530350D02*
X259000D01*
X258500Y529850D01*
G01X256500D02*
Y530850D01*
G01X243400Y558100D02*
Y554100D01*
X236000D01*
G01X243400Y553900D02*
Y549900D01*
X236000D01*
G01X249983Y500667D02*
Y503167D01*
X248942D01*
X248608Y503042D01*
X248400Y502875D01*
X248317Y502542D01*
X248400Y502209D01*
X248650Y502000D01*
X248942Y501875D01*
X249983D01*
G01X248942D02*
X248317Y500667D01*
G01X246133D02*
X246050Y501209D01*
X245925Y501667D01*
X245758Y502084D01*
X245550Y502542D01*
X245217Y503167D01*
X246883D01*
G01X242950D02*
X243283Y503084D01*
X243533Y502875D01*
X243700Y502625D01*
X243825Y502292D01*
X243867Y501917D01*
X243825Y501542D01*
X243700Y501209D01*
X243533Y500959D01*
X243283Y500750D01*
X242950Y500667D01*
X242617Y500750D01*
X242367Y500959D01*
X242200Y501209D01*
X242075Y501542D01*
X242033Y501917D01*
X242075Y502292D01*
X242200Y502625D01*
X242367Y502875D01*
X242617Y503084D01*
X242950Y503167D01*
G01X239850Y500667D02*
X239558Y500709D01*
X239225Y500834D01*
X239017Y501042D01*
X238933Y501334D01*
X239017Y501625D01*
X239267Y501875D01*
X239642Y502000D01*
X240058D01*
X240308Y502084D01*
X240517Y502292D01*
X240600Y502584D01*
X240475Y502875D01*
X240183Y503084D01*
X239850Y503167D01*
X239517Y503084D01*
X239225Y502875D01*
X239100Y502584D01*
X239183Y502292D01*
X239392Y502084D01*
X239642Y502000D01*
X240058D01*
X240433Y501875D01*
X240683Y501625D01*
X240767Y501334D01*
X240683Y501042D01*
X240475Y500834D01*
X240142Y500709D01*
X239850Y500667D01*
G01X235100Y507300D02*
Y503300D01*
X227700D01*
G01X276072Y550768D02*
Y553268D01*
X275031D01*
X274697Y553143D01*
X274489Y552976D01*
X274406Y552643D01*
X274489Y552310D01*
X274739Y552101D01*
X275031Y551976D01*
X276072D01*
G01X275031D02*
X274406Y550768D01*
G01X272931Y551810D02*
X272639Y552101D01*
X272389Y552268D01*
X272056Y552351D01*
X271764Y552268D01*
X271556Y552101D01*
X271389Y551851D01*
X271347Y551560D01*
X271389Y551310D01*
X271556Y551060D01*
X271806Y550851D01*
X272097Y550768D01*
X272431Y550851D01*
X272722Y551101D01*
X272889Y551476D01*
X272931Y551893D01*
X272847Y552435D01*
X272722Y552726D01*
X272514Y553018D01*
X272222Y553226D01*
X271931Y553268D01*
X271639Y553185D01*
X271431Y552976D01*
G01X269039Y553268D02*
X269372Y553185D01*
X269622Y552976D01*
X269789Y552726D01*
X269914Y552393D01*
X269956Y552018D01*
X269914Y551643D01*
X269789Y551310D01*
X269622Y551060D01*
X269372Y550851D01*
X269039Y550768D01*
X268706Y550851D01*
X268456Y551060D01*
X268289Y551310D01*
X268164Y551643D01*
X268122Y552018D01*
X268164Y552393D01*
X268289Y552726D01*
X268456Y552976D01*
X268706Y553185D01*
X269039Y553268D01*
G01X265939Y550768D02*
Y553268D01*
X266439Y552768D01*
G01Y550768D02*
X265439D01*
G01X261261Y550308D02*
Y546308D01*
X253861D01*
G01X273715Y515707D02*
Y518207D01*
X272674D01*
X272340Y518082D01*
X272132Y517915D01*
X272049Y517582D01*
X272132Y517249D01*
X272382Y517040D01*
X272674Y516915D01*
X273715D01*
G01X272674D02*
X272049Y515707D01*
G01X270699Y516082D02*
X270449Y515874D01*
X270157Y515749D01*
X269782Y515707D01*
X269407Y515790D01*
X269115Y515957D01*
X268907Y516249D01*
X268865Y516582D01*
X268949Y516915D01*
X269157Y517124D01*
X269449Y517290D01*
X269740Y517332D01*
X270032Y517290D01*
X270407Y517124D01*
X270282Y518207D01*
X269157D01*
G01X267390Y515999D02*
X267099Y515790D01*
X266765Y515707D01*
X266432Y515790D01*
X266140Y516040D01*
X265932Y516415D01*
X265849Y516790D01*
Y517249D01*
X265932Y517624D01*
X266140Y517957D01*
X266390Y518124D01*
X266682Y518207D01*
X267015Y518124D01*
X267265Y517957D01*
X267432Y517707D01*
X267515Y517374D01*
X267432Y517082D01*
X267224Y516790D01*
X266974Y516624D01*
X266682Y516582D01*
X266349Y516665D01*
X266099Y516874D01*
X265849Y517249D01*
G01X264290Y515999D02*
X263999Y515790D01*
X263665Y515707D01*
X263332Y515790D01*
X263040Y516040D01*
X262832Y516415D01*
X262749Y516790D01*
Y517249D01*
X262832Y517624D01*
X263040Y517957D01*
X263290Y518124D01*
X263582Y518207D01*
X263915Y518124D01*
X264165Y517957D01*
X264332Y517707D01*
X264415Y517374D01*
X264332Y517082D01*
X264124Y516790D01*
X263874Y516624D01*
X263582Y516582D01*
X263249Y516665D01*
X262999Y516874D01*
X262749Y517249D01*
G01X260700Y520217D02*
X263200D01*
Y521258D01*
X263075Y521592D01*
X262908Y521800D01*
X262575Y521883D01*
X262242Y521800D01*
X262033Y521550D01*
X261908Y521258D01*
Y520217D01*
G01Y521258D02*
X260700Y521883D01*
G01X261742Y523358D02*
X262033Y523650D01*
X262200Y523900D01*
X262283Y524233D01*
X262200Y524525D01*
X262033Y524733D01*
X261783Y524900D01*
X261492Y524942D01*
X261242Y524900D01*
X260992Y524733D01*
X260783Y524483D01*
X260700Y524192D01*
X260783Y523858D01*
X261033Y523567D01*
X261408Y523400D01*
X261825Y523358D01*
X262367Y523442D01*
X262658Y523567D01*
X262950Y523775D01*
X263158Y524067D01*
X263200Y524358D01*
X263117Y524650D01*
X262908Y524858D01*
G01X263200Y527250D02*
X263117Y526917D01*
X262908Y526667D01*
X262658Y526500D01*
X262325Y526375D01*
X261950Y526333D01*
X261575Y526375D01*
X261242Y526500D01*
X260992Y526667D01*
X260783Y526917D01*
X260700Y527250D01*
X260783Y527583D01*
X260992Y527833D01*
X261242Y528000D01*
X261575Y528125D01*
X261950Y528167D01*
X262325Y528125D01*
X262658Y528000D01*
X262908Y527833D01*
X263117Y527583D01*
X263200Y527250D01*
G01X260700Y530267D02*
X261242Y530350D01*
X261700Y530475D01*
X262117Y530642D01*
X262575Y530850D01*
X263200Y531183D01*
Y529517D01*
G01X287027Y515887D02*
Y518387D01*
X285986D01*
X285652Y518262D01*
X285444Y518095D01*
X285361Y517762D01*
X285444Y517429D01*
X285694Y517220D01*
X285986Y517095D01*
X287027D01*
G01X285986D02*
X285361Y515887D01*
G01X283177D02*
X283094Y516429D01*
X282969Y516887D01*
X282802Y517304D01*
X282594Y517762D01*
X282261Y518387D01*
X283927D01*
G01X279994Y515887D02*
X279702Y515929D01*
X279369Y516054D01*
X279161Y516262D01*
X279077Y516554D01*
X279161Y516845D01*
X279411Y517095D01*
X279786Y517220D01*
X280202D01*
X280452Y517304D01*
X280661Y517512D01*
X280744Y517804D01*
X280619Y518095D01*
X280327Y518304D01*
X279994Y518387D01*
X279661Y518304D01*
X279369Y518095D01*
X279244Y517804D01*
X279327Y517512D01*
X279536Y517304D01*
X279786Y517220D01*
X280202D01*
X280577Y517095D01*
X280827Y516845D01*
X280911Y516554D01*
X280827Y516262D01*
X280619Y516054D01*
X280286Y515929D01*
X279994Y515887D01*
G01X276394D02*
Y518387D01*
X277936Y516595D01*
X275852D01*
G01X214053Y526088D02*
Y530088D01*
X221453D01*
G01X265000Y534017D02*
X267500D01*
Y535058D01*
X267375Y535392D01*
X267208Y535600D01*
X266875Y535683D01*
X266542Y535600D01*
X266333Y535350D01*
X266208Y535058D01*
Y534017D01*
G01Y535058D02*
X265000Y535683D01*
G01Y537867D02*
X265542Y537950D01*
X266000Y538075D01*
X266417Y538242D01*
X266875Y538450D01*
X267500Y538783D01*
Y537117D01*
G01X267083Y540258D02*
X267333Y540508D01*
X267458Y540800D01*
X267500Y541133D01*
X267417Y541550D01*
X267208Y541842D01*
X266958Y541925D01*
X266708Y541883D01*
X266500Y541717D01*
X266083Y540883D01*
X265792Y540508D01*
X265375Y540258D01*
X265000Y540175D01*
Y541925D01*
G01X265292Y543442D02*
X265083Y543733D01*
X265000Y544067D01*
X265083Y544400D01*
X265333Y544692D01*
X265708Y544900D01*
X266083Y544983D01*
X266542D01*
X266917Y544900D01*
X267250Y544692D01*
X267417Y544442D01*
X267500Y544150D01*
X267417Y543817D01*
X267250Y543567D01*
X267000Y543400D01*
X266667Y543317D01*
X266375Y543400D01*
X266083Y543608D01*
X265917Y543858D01*
X265875Y544150D01*
X265958Y544483D01*
X266167Y544733D01*
X266542Y544983D01*
G01X253000Y538200D02*
Y534200D01*
X245600D01*
G01X268500Y534017D02*
X271000D01*
Y535058D01*
X270875Y535392D01*
X270708Y535600D01*
X270375Y535683D01*
X270042Y535600D01*
X269833Y535350D01*
X269708Y535058D01*
Y534017D01*
G01Y535058D02*
X268500Y535683D01*
G01Y537867D02*
X269042Y537950D01*
X269500Y538075D01*
X269917Y538242D01*
X270375Y538450D01*
X271000Y538783D01*
Y537117D01*
G01X268500Y541050D02*
X268542Y541342D01*
X268667Y541675D01*
X268875Y541883D01*
X269167Y541967D01*
X269458Y541883D01*
X269708Y541633D01*
X269833Y541258D01*
Y540842D01*
X269917Y540592D01*
X270125Y540383D01*
X270417Y540300D01*
X270708Y540425D01*
X270917Y540717D01*
X271000Y541050D01*
X270917Y541383D01*
X270708Y541675D01*
X270417Y541800D01*
X270125Y541717D01*
X269917Y541508D01*
X269833Y541258D01*
Y540842D01*
X269708Y540467D01*
X269458Y540217D01*
X269167Y540133D01*
X268875Y540217D01*
X268667Y540425D01*
X268542Y540758D01*
X268500Y541050D01*
G01X268875Y543233D02*
X268667Y543483D01*
X268542Y543775D01*
X268500Y544150D01*
X268583Y544525D01*
X268750Y544817D01*
X269042Y545025D01*
X269375Y545067D01*
X269708Y544983D01*
X269917Y544775D01*
X270083Y544483D01*
X270125Y544192D01*
X270083Y543900D01*
X269917Y543525D01*
X271000Y543650D01*
Y544775D01*
G01X260600Y537800D02*
Y533800D01*
X253200D01*
G01X293700Y527500D02*
Y525000D01*
G01X294658Y527500D02*
X292742D01*
G01X291433Y525000D02*
Y527500D01*
X290433D01*
X290100Y527375D01*
X289850Y527083D01*
X289767Y526750D01*
X289850Y526417D01*
X290058Y526167D01*
X290433Y526042D01*
X291433D01*
G01X288292Y527083D02*
X288042Y527333D01*
X287750Y527458D01*
X287417Y527500D01*
X287000Y527417D01*
X286708Y527208D01*
X286625Y526958D01*
X286667Y526708D01*
X286833Y526500D01*
X287667Y526083D01*
X288042Y525792D01*
X288292Y525375D01*
X288375Y525000D01*
X286625D01*
G01X284400Y527500D02*
X284733Y527417D01*
X284983Y527208D01*
X285150Y526958D01*
X285275Y526625D01*
X285317Y526250D01*
X285275Y525875D01*
X285150Y525542D01*
X284983Y525292D01*
X284733Y525083D01*
X284400Y525000D01*
X284067Y525083D01*
X283817Y525292D01*
X283650Y525542D01*
X283525Y525875D01*
X283483Y526250D01*
X283525Y526625D01*
X283650Y526958D01*
X283817Y527208D01*
X284067Y527417D01*
X284400Y527500D01*
G01X282217Y525375D02*
X281967Y525167D01*
X281675Y525042D01*
X281300Y525000D01*
X280925Y525083D01*
X280633Y525250D01*
X280425Y525542D01*
X280383Y525875D01*
X280467Y526208D01*
X280675Y526417D01*
X280967Y526583D01*
X281258Y526625D01*
X281550Y526583D01*
X281925Y526417D01*
X281800Y527500D01*
X280675D01*
G01X294200Y523900D02*
Y521400D01*
G01X295158Y523900D02*
X293242D01*
G01X291933Y521400D02*
Y523900D01*
X290933D01*
X290600Y523775D01*
X290350Y523483D01*
X290267Y523150D01*
X290350Y522817D01*
X290558Y522567D01*
X290933Y522442D01*
X291933D01*
G01X288792Y523483D02*
X288542Y523733D01*
X288250Y523858D01*
X287917Y523900D01*
X287500Y523817D01*
X287208Y523608D01*
X287125Y523358D01*
X287167Y523108D01*
X287333Y522900D01*
X288167Y522483D01*
X288542Y522192D01*
X288792Y521775D01*
X288875Y521400D01*
X287125D01*
G01X284900Y523900D02*
X285233Y523817D01*
X285483Y523608D01*
X285650Y523358D01*
X285775Y523025D01*
X285817Y522650D01*
X285775Y522275D01*
X285650Y521942D01*
X285483Y521692D01*
X285233Y521483D01*
X284900Y521400D01*
X284567Y521483D01*
X284317Y521692D01*
X284150Y521942D01*
X284025Y522275D01*
X283983Y522650D01*
X284025Y523025D01*
X284150Y523358D01*
X284317Y523608D01*
X284567Y523817D01*
X284900Y523900D01*
G01X282592Y522442D02*
X282300Y522733D01*
X282050Y522900D01*
X281717Y522983D01*
X281425Y522900D01*
X281217Y522733D01*
X281050Y522483D01*
X281008Y522192D01*
X281050Y521942D01*
X281217Y521692D01*
X281467Y521483D01*
X281758Y521400D01*
X282092Y521483D01*
X282383Y521733D01*
X282550Y522108D01*
X282592Y522525D01*
X282508Y523067D01*
X282383Y523358D01*
X282175Y523650D01*
X281883Y523858D01*
X281592Y523900D01*
X281300Y523817D01*
X281092Y523608D01*
G01X275650Y549000D02*
Y546500D01*
G01X276608Y549000D02*
X274692D01*
G01X273383Y546500D02*
Y549000D01*
X272383D01*
X272050Y548875D01*
X271800Y548583D01*
X271717Y548250D01*
X271800Y547917D01*
X272008Y547667D01*
X272383Y547542D01*
X273383D01*
G01X269450Y546500D02*
Y549000D01*
X269950Y548500D01*
G01Y546500D02*
X268950D01*
G01X267267Y547000D02*
X267017Y546708D01*
X266683Y546542D01*
X266308Y546500D01*
X265975Y546542D01*
X265642Y546750D01*
X265433Y547000D01*
X265392Y547250D01*
X265475Y547542D01*
X265767Y547750D01*
X266058Y547833D01*
X266433D01*
G01X266058D02*
X265808Y547958D01*
X265600Y548167D01*
X265517Y548417D01*
X265600Y548667D01*
X265808Y548875D01*
X266183Y549000D01*
X266558Y548958D01*
X266933Y548792D01*
G01X221600Y494280D02*
Y507680D01*
G01X289383Y546492D02*
X289633Y546617D01*
X289925Y546700D01*
X290258D01*
X290633Y546575D01*
X290925Y546367D01*
X291133Y546117D01*
X291300Y545700D01*
X291342Y545325D01*
X291258Y544950D01*
X291133Y544700D01*
X290883Y544450D01*
X290592Y544283D01*
X290300Y544200D01*
X290008D01*
X289717Y544283D01*
X289467Y544408D01*
X289258Y544575D01*
G01X287200Y544200D02*
X286908Y544242D01*
X286575Y544367D01*
X286367Y544575D01*
X286283Y544867D01*
X286367Y545158D01*
X286617Y545408D01*
X286992Y545533D01*
X287408D01*
X287658Y545617D01*
X287867Y545825D01*
X287950Y546117D01*
X287825Y546408D01*
X287533Y546617D01*
X287200Y546700D01*
X286867Y546617D01*
X286575Y546408D01*
X286450Y546117D01*
X286533Y545825D01*
X286742Y545617D01*
X286992Y545533D01*
X287408D01*
X287783Y545408D01*
X288033Y545158D01*
X288117Y544867D01*
X288033Y544575D01*
X287825Y544367D01*
X287492Y544242D01*
X287200Y544200D01*
G01X285017Y544700D02*
X284767Y544408D01*
X284433Y544242D01*
X284058Y544200D01*
X283725Y544242D01*
X283392Y544450D01*
X283183Y544700D01*
X283142Y544950D01*
X283225Y545242D01*
X283517Y545450D01*
X283808Y545533D01*
X284183D01*
G01X283808D02*
X283558Y545658D01*
X283350Y545867D01*
X283267Y546117D01*
X283350Y546367D01*
X283558Y546575D01*
X283933Y546700D01*
X284308Y546658D01*
X284683Y546492D01*
G01X253492Y507567D02*
X253617Y507317D01*
X253700Y507025D01*
Y506692D01*
X253575Y506317D01*
X253367Y506025D01*
X253117Y505817D01*
X252700Y505650D01*
X252325Y505608D01*
X251950Y505692D01*
X251700Y505817D01*
X251450Y506067D01*
X251283Y506358D01*
X251200Y506650D01*
Y506942D01*
X251283Y507233D01*
X251408Y507483D01*
X251575Y507692D01*
G01X251200Y509750D02*
X253700D01*
X253200Y509250D01*
G01X251200D02*
Y510250D01*
G01Y512850D02*
X253700D01*
X253200Y512350D01*
G01X251200D02*
Y513350D01*
G01Y516450D02*
X253700D01*
X251908Y514908D01*
Y516992D01*
G01X242392Y507567D02*
X242517Y507317D01*
X242600Y507025D01*
Y506692D01*
X242475Y506317D01*
X242267Y506025D01*
X242017Y505817D01*
X241600Y505650D01*
X241225Y505608D01*
X240850Y505692D01*
X240600Y505817D01*
X240350Y506067D01*
X240183Y506358D01*
X240100Y506650D01*
Y506942D01*
X240183Y507233D01*
X240308Y507483D01*
X240475Y507692D01*
G01X240100Y509750D02*
X242600D01*
X242100Y509250D01*
G01X240100D02*
Y510250D01*
G01Y512850D02*
X242600D01*
X242100Y512350D01*
G01X240100D02*
Y513350D01*
G01X240600Y515033D02*
X240308Y515283D01*
X240142Y515617D01*
X240100Y515992D01*
X240142Y516325D01*
X240350Y516658D01*
X240600Y516867D01*
X240850Y516908D01*
X241142Y516825D01*
X241350Y516533D01*
X241433Y516242D01*
Y515867D01*
G01Y516242D02*
X241558Y516492D01*
X241767Y516700D01*
X242017Y516783D01*
X242267Y516700D01*
X242475Y516492D01*
X242600Y516117D01*
X242558Y515742D01*
X242392Y515367D01*
G01X238692Y507567D02*
X238817Y507317D01*
X238900Y507025D01*
Y506692D01*
X238775Y506317D01*
X238567Y506025D01*
X238317Y505817D01*
X237900Y505650D01*
X237525Y505608D01*
X237150Y505692D01*
X236900Y505817D01*
X236650Y506067D01*
X236483Y506358D01*
X236400Y506650D01*
Y506942D01*
X236483Y507233D01*
X236608Y507483D01*
X236775Y507692D01*
G01X236400Y509750D02*
X238900D01*
X238400Y509250D01*
G01X236400D02*
Y510250D01*
G01Y512850D02*
X238900D01*
X238400Y512350D01*
G01X236400D02*
Y513350D01*
G01X238900Y515950D02*
X238817Y515617D01*
X238608Y515367D01*
X238358Y515200D01*
X238025Y515075D01*
X237650Y515033D01*
X237275Y515075D01*
X236942Y515200D01*
X236692Y515367D01*
X236483Y515617D01*
X236400Y515950D01*
X236483Y516283D01*
X236692Y516533D01*
X236942Y516700D01*
X237275Y516825D01*
X237650Y516867D01*
X238025Y516825D01*
X238358Y516700D01*
X238608Y516533D01*
X238817Y516283D01*
X238900Y515950D01*
G01X246092Y507567D02*
X246217Y507317D01*
X246300Y507025D01*
Y506692D01*
X246175Y506317D01*
X245967Y506025D01*
X245717Y505817D01*
X245300Y505650D01*
X244925Y505608D01*
X244550Y505692D01*
X244300Y505817D01*
X244050Y506067D01*
X243883Y506358D01*
X243800Y506650D01*
Y506942D01*
X243883Y507233D01*
X244008Y507483D01*
X244175Y507692D01*
G01X243800Y509750D02*
X246300D01*
X245800Y509250D01*
G01X243800D02*
Y510250D01*
G01X246300Y512850D02*
X246217Y512517D01*
X246008Y512267D01*
X245758Y512100D01*
X245425Y511975D01*
X245050Y511933D01*
X244675Y511975D01*
X244342Y512100D01*
X244092Y512267D01*
X243883Y512517D01*
X243800Y512850D01*
X243883Y513183D01*
X244092Y513433D01*
X244342Y513600D01*
X244675Y513725D01*
X245050Y513767D01*
X245425Y513725D01*
X245758Y513600D01*
X246008Y513433D01*
X246217Y513183D01*
X246300Y512850D01*
G01X244092Y515242D02*
X243883Y515533D01*
X243800Y515867D01*
X243883Y516200D01*
X244133Y516492D01*
X244508Y516700D01*
X244883Y516783D01*
X245342D01*
X245717Y516700D01*
X246050Y516492D01*
X246217Y516242D01*
X246300Y515950D01*
X246217Y515617D01*
X246050Y515367D01*
X245800Y515200D01*
X245467Y515117D01*
X245175Y515200D01*
X244883Y515408D01*
X244717Y515658D01*
X244675Y515950D01*
X244758Y516283D01*
X244967Y516533D01*
X245342Y516783D01*
G01X249792Y507567D02*
X249917Y507317D01*
X250000Y507025D01*
Y506692D01*
X249875Y506317D01*
X249667Y506025D01*
X249417Y505817D01*
X249000Y505650D01*
X248625Y505608D01*
X248250Y505692D01*
X248000Y505817D01*
X247750Y506067D01*
X247583Y506358D01*
X247500Y506650D01*
Y506942D01*
X247583Y507233D01*
X247708Y507483D01*
X247875Y507692D01*
G01X247500Y509750D02*
X250000D01*
X249500Y509250D01*
G01X247500D02*
Y510250D01*
G01Y512850D02*
X250000D01*
X249500Y512350D01*
G01X247500D02*
Y513350D01*
G01X247875Y515033D02*
X247667Y515283D01*
X247542Y515575D01*
X247500Y515950D01*
X247583Y516325D01*
X247750Y516617D01*
X248042Y516825D01*
X248375Y516867D01*
X248708Y516783D01*
X248917Y516575D01*
X249083Y516283D01*
X249125Y515992D01*
X249083Y515700D01*
X248917Y515325D01*
X250000Y515450D01*
Y516575D01*
G01X259172Y635057D02*
X259297Y634807D01*
X259380Y634515D01*
Y634182D01*
X259255Y633807D01*
X259047Y633515D01*
X258797Y633307D01*
X258380Y633140D01*
X258005Y633098D01*
X257630Y633182D01*
X257380Y633307D01*
X257130Y633557D01*
X256963Y633848D01*
X256880Y634140D01*
Y634432D01*
X256963Y634723D01*
X257088Y634973D01*
X257255Y635182D01*
G01X256880Y637240D02*
X256922Y637532D01*
X257047Y637865D01*
X257255Y638073D01*
X257547Y638157D01*
X257838Y638073D01*
X258088Y637823D01*
X258213Y637448D01*
Y637032D01*
X258297Y636782D01*
X258505Y636573D01*
X258797Y636490D01*
X259088Y636615D01*
X259297Y636907D01*
X259380Y637240D01*
X259297Y637573D01*
X259088Y637865D01*
X258797Y637990D01*
X258505Y637907D01*
X258297Y637698D01*
X258213Y637448D01*
Y637032D01*
X258088Y636657D01*
X257838Y636407D01*
X257547Y636323D01*
X257255Y636407D01*
X257047Y636615D01*
X256922Y636948D01*
X256880Y637240D01*
G01Y640340D02*
X256922Y640632D01*
X257047Y640965D01*
X257255Y641173D01*
X257547Y641257D01*
X257838Y641173D01*
X258088Y640923D01*
X258213Y640548D01*
Y640132D01*
X258297Y639882D01*
X258505Y639673D01*
X258797Y639590D01*
X259088Y639715D01*
X259297Y640007D01*
X259380Y640340D01*
X259297Y640673D01*
X259088Y640965D01*
X258797Y641090D01*
X258505Y641007D01*
X258297Y640798D01*
X258213Y640548D01*
Y640132D01*
X258088Y639757D01*
X257838Y639507D01*
X257547Y639423D01*
X257255Y639507D01*
X257047Y639715D01*
X256922Y640048D01*
X256880Y640340D01*
G01X248683Y606792D02*
X248933Y606917D01*
X249225Y607000D01*
X249558D01*
X249933Y606875D01*
X250225Y606667D01*
X250433Y606417D01*
X250600Y606000D01*
X250642Y605625D01*
X250558Y605250D01*
X250433Y605000D01*
X250183Y604750D01*
X249892Y604583D01*
X249600Y604500D01*
X249308D01*
X249017Y604583D01*
X248767Y604708D01*
X248558Y604875D01*
G01X246500Y604500D02*
X246208Y604542D01*
X245875Y604667D01*
X245667Y604875D01*
X245583Y605167D01*
X245667Y605458D01*
X245917Y605708D01*
X246292Y605833D01*
X246708D01*
X246958Y605917D01*
X247167Y606125D01*
X247250Y606417D01*
X247125Y606708D01*
X246833Y606917D01*
X246500Y607000D01*
X246167Y606917D01*
X245875Y606708D01*
X245750Y606417D01*
X245833Y606125D01*
X246042Y605917D01*
X246292Y605833D01*
X246708D01*
X247083Y605708D01*
X247333Y605458D01*
X247417Y605167D01*
X247333Y604875D01*
X247125Y604667D01*
X246792Y604542D01*
X246500Y604500D01*
G01X243400Y607000D02*
X243733Y606917D01*
X243983Y606708D01*
X244150Y606458D01*
X244275Y606125D01*
X244317Y605750D01*
X244275Y605375D01*
X244150Y605042D01*
X243983Y604792D01*
X243733Y604583D01*
X243400Y604500D01*
X243067Y604583D01*
X242817Y604792D01*
X242650Y605042D01*
X242525Y605375D01*
X242483Y605750D01*
X242525Y606125D01*
X242650Y606458D01*
X242817Y606708D01*
X243067Y606917D01*
X243400Y607000D01*
G01X288882Y604260D02*
X289132Y604385D01*
X289424Y604468D01*
X289757D01*
X290132Y604343D01*
X290424Y604135D01*
X290632Y603885D01*
X290799Y603468D01*
X290841Y603093D01*
X290757Y602718D01*
X290632Y602468D01*
X290382Y602218D01*
X290091Y602051D01*
X289799Y601968D01*
X289507D01*
X289216Y602051D01*
X288966Y602176D01*
X288757Y602343D01*
G01X286199Y601968D02*
Y604468D01*
X287741Y602676D01*
X285657D01*
G01X283599Y601968D02*
Y604468D01*
X284099Y603968D01*
G01Y601968D02*
X283099D01*
G01X260579Y621384D02*
X260704Y621134D01*
X260787Y620842D01*
Y620509D01*
X260662Y620134D01*
X260454Y619842D01*
X260204Y619634D01*
X259787Y619467D01*
X259412Y619425D01*
X259037Y619509D01*
X258787Y619634D01*
X258537Y619884D01*
X258370Y620175D01*
X258287Y620467D01*
Y620759D01*
X258370Y621050D01*
X258495Y621300D01*
X258662Y621509D01*
G01X258287Y623567D02*
X258329Y623859D01*
X258454Y624192D01*
X258662Y624400D01*
X258954Y624484D01*
X259245Y624400D01*
X259495Y624150D01*
X259620Y623775D01*
Y623359D01*
X259704Y623109D01*
X259912Y622900D01*
X260204Y622817D01*
X260495Y622942D01*
X260704Y623234D01*
X260787Y623567D01*
X260704Y623900D01*
X260495Y624192D01*
X260204Y624317D01*
X259912Y624234D01*
X259704Y624025D01*
X259620Y623775D01*
Y623359D01*
X259495Y622984D01*
X259245Y622734D01*
X258954Y622650D01*
X258662Y622734D01*
X258454Y622942D01*
X258329Y623275D01*
X258287Y623567D01*
G01Y626667D02*
X260787D01*
X260287Y626167D01*
G01X258287D02*
Y627167D01*
G01X230000Y605017D02*
X232500D01*
Y606058D01*
X232375Y606392D01*
X232208Y606600D01*
X231875Y606683D01*
X231542Y606600D01*
X231333Y606350D01*
X231208Y606058D01*
Y605017D01*
G01Y606058D02*
X230000Y606683D01*
G01X230500Y608033D02*
X230208Y608283D01*
X230042Y608617D01*
X230000Y608992D01*
X230042Y609325D01*
X230250Y609658D01*
X230500Y609867D01*
X230750Y609908D01*
X231042Y609825D01*
X231250Y609533D01*
X231333Y609242D01*
Y608867D01*
G01Y609242D02*
X231458Y609492D01*
X231667Y609700D01*
X231917Y609783D01*
X232167Y609700D01*
X232375Y609492D01*
X232500Y609117D01*
X232458Y608742D01*
X232292Y608367D01*
G01X232500Y612050D02*
X232417Y611717D01*
X232208Y611467D01*
X231958Y611300D01*
X231625Y611175D01*
X231250Y611133D01*
X230875Y611175D01*
X230542Y611300D01*
X230292Y611467D01*
X230083Y611717D01*
X230000Y612050D01*
X230083Y612383D01*
X230292Y612633D01*
X230542Y612800D01*
X230875Y612925D01*
X231250Y612967D01*
X231625Y612925D01*
X231958Y612800D01*
X232208Y612633D01*
X232417Y612383D01*
X232500Y612050D01*
G01X230000Y615650D02*
X232500D01*
X230708Y614108D01*
Y616192D01*
G01X219800Y613700D02*
X223800D01*
Y606300D01*
G01X234000Y601517D02*
X236500D01*
Y602558D01*
X236375Y602892D01*
X236208Y603100D01*
X235875Y603183D01*
X235542Y603100D01*
X235333Y602850D01*
X235208Y602558D01*
Y601517D01*
G01Y602558D02*
X234000Y603183D01*
G01X234500Y604533D02*
X234208Y604783D01*
X234042Y605117D01*
X234000Y605492D01*
X234042Y605825D01*
X234250Y606158D01*
X234500Y606367D01*
X234750Y606408D01*
X235042Y606325D01*
X235250Y606033D01*
X235333Y605742D01*
Y605367D01*
G01Y605742D02*
X235458Y605992D01*
X235667Y606200D01*
X235917Y606283D01*
X236167Y606200D01*
X236375Y605992D01*
X236500Y605617D01*
X236458Y605242D01*
X236292Y604867D01*
G01X236500Y608550D02*
X236417Y608217D01*
X236208Y607967D01*
X235958Y607800D01*
X235625Y607675D01*
X235250Y607633D01*
X234875Y607675D01*
X234542Y607800D01*
X234292Y607967D01*
X234083Y608217D01*
X234000Y608550D01*
X234083Y608883D01*
X234292Y609133D01*
X234542Y609300D01*
X234875Y609425D01*
X235250Y609467D01*
X235625Y609425D01*
X235958Y609300D01*
X236208Y609133D01*
X236417Y608883D01*
X236500Y608550D01*
G01X234500Y610733D02*
X234208Y610983D01*
X234042Y611317D01*
X234000Y611692D01*
X234042Y612025D01*
X234250Y612358D01*
X234500Y612567D01*
X234750Y612608D01*
X235042Y612525D01*
X235250Y612233D01*
X235333Y611942D01*
Y611567D01*
G01Y611942D02*
X235458Y612192D01*
X235667Y612400D01*
X235917Y612483D01*
X236167Y612400D01*
X236375Y612192D01*
X236500Y611817D01*
X236458Y611442D01*
X236292Y611067D01*
G01X223900Y613600D02*
X227900D01*
Y606200D01*
G01X220108Y635894D02*
Y639894D01*
X227508D01*
G01X222148Y579666D02*
Y583666D01*
X229548D01*
G01X232483Y626000D02*
Y628500D01*
X231442D01*
X231108Y628375D01*
X230900Y628208D01*
X230817Y627875D01*
X230900Y627542D01*
X231150Y627333D01*
X231442Y627208D01*
X232483D01*
G01X231442D02*
X230817Y626000D01*
G01X229467Y626500D02*
X229217Y626208D01*
X228883Y626042D01*
X228508Y626000D01*
X228175Y626042D01*
X227842Y626250D01*
X227633Y626500D01*
X227592Y626750D01*
X227675Y627042D01*
X227967Y627250D01*
X228258Y627333D01*
X228633D01*
G01X228258D02*
X228008Y627458D01*
X227800Y627667D01*
X227717Y627917D01*
X227800Y628167D01*
X228008Y628375D01*
X228383Y628500D01*
X228758Y628458D01*
X229133Y628292D01*
G01X226158Y626292D02*
X225867Y626083D01*
X225533Y626000D01*
X225200Y626083D01*
X224908Y626333D01*
X224700Y626708D01*
X224617Y627083D01*
Y627542D01*
X224700Y627917D01*
X224908Y628250D01*
X225158Y628417D01*
X225450Y628500D01*
X225783Y628417D01*
X226033Y628250D01*
X226200Y628000D01*
X226283Y627667D01*
X226200Y627375D01*
X225992Y627083D01*
X225742Y626917D01*
X225450Y626875D01*
X225117Y626958D01*
X224867Y627167D01*
X224617Y627542D01*
G01X223058Y626292D02*
X222767Y626083D01*
X222433Y626000D01*
X222100Y626083D01*
X221808Y626333D01*
X221600Y626708D01*
X221517Y627083D01*
Y627542D01*
X221600Y627917D01*
X221808Y628250D01*
X222058Y628417D01*
X222350Y628500D01*
X222683Y628417D01*
X222933Y628250D01*
X223100Y628000D01*
X223183Y627667D01*
X223100Y627375D01*
X222892Y627083D01*
X222642Y626917D01*
X222350Y626875D01*
X222017Y626958D01*
X221767Y627167D01*
X221517Y627542D01*
G01X226000Y617300D02*
X222000D01*
Y624700D01*
G01X266683Y592661D02*
Y595161D01*
X265642D01*
X265308Y595036D01*
X265100Y594869D01*
X265017Y594536D01*
X265100Y594203D01*
X265350Y593994D01*
X265642Y593869D01*
X266683D01*
G01X265642D02*
X265017Y592661D01*
G01X263667Y593161D02*
X263417Y592869D01*
X263083Y592703D01*
X262708Y592661D01*
X262375Y592703D01*
X262042Y592911D01*
X261833Y593161D01*
X261792Y593411D01*
X261875Y593703D01*
X262167Y593911D01*
X262458Y593994D01*
X262833D01*
G01X262458D02*
X262208Y594119D01*
X262000Y594328D01*
X261917Y594578D01*
X262000Y594828D01*
X262208Y595036D01*
X262583Y595161D01*
X262958Y595119D01*
X263333Y594953D01*
G01X260358Y592953D02*
X260067Y592744D01*
X259733Y592661D01*
X259400Y592744D01*
X259108Y592994D01*
X258900Y593369D01*
X258817Y593744D01*
Y594203D01*
X258900Y594578D01*
X259108Y594911D01*
X259358Y595078D01*
X259650Y595161D01*
X259983Y595078D01*
X260233Y594911D01*
X260400Y594661D01*
X260483Y594328D01*
X260400Y594036D01*
X260192Y593744D01*
X259942Y593578D01*
X259650Y593536D01*
X259317Y593619D01*
X259067Y593828D01*
X258817Y594203D01*
G01X256550Y592661D02*
X256258Y592703D01*
X255925Y592828D01*
X255717Y593036D01*
X255633Y593328D01*
X255717Y593619D01*
X255967Y593869D01*
X256342Y593994D01*
X256758D01*
X257008Y594078D01*
X257217Y594286D01*
X257300Y594578D01*
X257175Y594869D01*
X256883Y595078D01*
X256550Y595161D01*
X256217Y595078D01*
X255925Y594869D01*
X255800Y594578D01*
X255883Y594286D01*
X256092Y594078D01*
X256342Y593994D01*
X256758D01*
X257133Y593869D01*
X257383Y593619D01*
X257467Y593328D01*
X257383Y593036D01*
X257175Y592828D01*
X256842Y592703D01*
X256550Y592661D01*
G01X240900Y595500D02*
Y591500D01*
X233500D01*
G01X237483Y629500D02*
Y632000D01*
X236442D01*
X236108Y631875D01*
X235900Y631708D01*
X235817Y631375D01*
X235900Y631042D01*
X236150Y630833D01*
X236442Y630708D01*
X237483D01*
G01X236442D02*
X235817Y629500D01*
G01X234467Y630000D02*
X234217Y629708D01*
X233883Y629542D01*
X233508Y629500D01*
X233175Y629542D01*
X232842Y629750D01*
X232633Y630000D01*
X232592Y630250D01*
X232675Y630542D01*
X232967Y630750D01*
X233258Y630833D01*
X233633D01*
G01X233258D02*
X233008Y630958D01*
X232800Y631167D01*
X232717Y631417D01*
X232800Y631667D01*
X233008Y631875D01*
X233383Y632000D01*
X233758Y631958D01*
X234133Y631792D01*
G01X231158Y629792D02*
X230867Y629583D01*
X230533Y629500D01*
X230200Y629583D01*
X229908Y629833D01*
X229700Y630208D01*
X229617Y630583D01*
Y631042D01*
X229700Y631417D01*
X229908Y631750D01*
X230158Y631917D01*
X230450Y632000D01*
X230783Y631917D01*
X231033Y631750D01*
X231200Y631500D01*
X231283Y631167D01*
X231200Y630875D01*
X230992Y630583D01*
X230742Y630417D01*
X230450Y630375D01*
X230117Y630458D01*
X229867Y630667D01*
X229617Y631042D01*
G01X226850Y629500D02*
Y632000D01*
X228392Y630208D01*
X226308D01*
G01X233592Y624802D02*
Y620802D01*
X226192D01*
G01X266683Y596661D02*
Y599161D01*
X265642D01*
X265308Y599036D01*
X265100Y598869D01*
X265017Y598536D01*
X265100Y598203D01*
X265350Y597994D01*
X265642Y597869D01*
X266683D01*
G01X265642D02*
X265017Y596661D01*
G01X263667Y597161D02*
X263417Y596869D01*
X263083Y596703D01*
X262708Y596661D01*
X262375Y596703D01*
X262042Y596911D01*
X261833Y597161D01*
X261792Y597411D01*
X261875Y597703D01*
X262167Y597911D01*
X262458Y597994D01*
X262833D01*
G01X262458D02*
X262208Y598119D01*
X262000Y598328D01*
X261917Y598578D01*
X262000Y598828D01*
X262208Y599036D01*
X262583Y599161D01*
X262958Y599119D01*
X263333Y598953D01*
G01X260358Y596953D02*
X260067Y596744D01*
X259733Y596661D01*
X259400Y596744D01*
X259108Y596994D01*
X258900Y597369D01*
X258817Y597744D01*
Y598203D01*
X258900Y598578D01*
X259108Y598911D01*
X259358Y599078D01*
X259650Y599161D01*
X259983Y599078D01*
X260233Y598911D01*
X260400Y598661D01*
X260483Y598328D01*
X260400Y598036D01*
X260192Y597744D01*
X259942Y597578D01*
X259650Y597536D01*
X259317Y597619D01*
X259067Y597828D01*
X258817Y598203D01*
G01X257467Y597161D02*
X257217Y596869D01*
X256883Y596703D01*
X256508Y596661D01*
X256175Y596703D01*
X255842Y596911D01*
X255633Y597161D01*
X255592Y597411D01*
X255675Y597703D01*
X255967Y597911D01*
X256258Y597994D01*
X256633D01*
G01X256258D02*
X256008Y598119D01*
X255800Y598328D01*
X255717Y598578D01*
X255800Y598828D01*
X256008Y599036D01*
X256383Y599161D01*
X256758Y599119D01*
X257133Y598953D01*
G01X233500Y595500D02*
Y599500D01*
X240900D01*
G01X279983Y596161D02*
Y598661D01*
X278942D01*
X278608Y598536D01*
X278400Y598369D01*
X278317Y598036D01*
X278400Y597703D01*
X278650Y597494D01*
X278942Y597369D01*
X279983D01*
G01X278942D02*
X278317Y596161D01*
G01X276967Y596661D02*
X276717Y596369D01*
X276383Y596203D01*
X276008Y596161D01*
X275675Y596203D01*
X275342Y596411D01*
X275133Y596661D01*
X275092Y596911D01*
X275175Y597203D01*
X275467Y597411D01*
X275758Y597494D01*
X276133D01*
G01X275758D02*
X275508Y597619D01*
X275300Y597828D01*
X275217Y598078D01*
X275300Y598328D01*
X275508Y598536D01*
X275883Y598661D01*
X276258Y598619D01*
X276633Y598453D01*
G01X272950Y596161D02*
X272658Y596203D01*
X272325Y596328D01*
X272117Y596536D01*
X272033Y596828D01*
X272117Y597119D01*
X272367Y597369D01*
X272742Y597494D01*
X273158D01*
X273408Y597578D01*
X273617Y597786D01*
X273700Y598078D01*
X273575Y598369D01*
X273283Y598578D01*
X272950Y598661D01*
X272617Y598578D01*
X272325Y598369D01*
X272200Y598078D01*
X272283Y597786D01*
X272492Y597578D01*
X272742Y597494D01*
X273158D01*
X273533Y597369D01*
X273783Y597119D01*
X273867Y596828D01*
X273783Y596536D01*
X273575Y596328D01*
X273242Y596203D01*
X272950Y596161D01*
G01X270642Y597203D02*
X270350Y597494D01*
X270100Y597661D01*
X269767Y597744D01*
X269475Y597661D01*
X269267Y597494D01*
X269100Y597244D01*
X269058Y596953D01*
X269100Y596703D01*
X269267Y596453D01*
X269517Y596244D01*
X269808Y596161D01*
X270142Y596244D01*
X270433Y596494D01*
X270600Y596869D01*
X270642Y597286D01*
X270558Y597828D01*
X270433Y598119D01*
X270225Y598411D01*
X269933Y598619D01*
X269642Y598661D01*
X269350Y598578D01*
X269142Y598369D01*
G01X263300Y586500D02*
Y590500D01*
X270700D01*
G01X240100Y581000D02*
X236100D01*
Y588400D01*
G01X253683Y596861D02*
Y599361D01*
X252642D01*
X252308Y599236D01*
X252100Y599069D01*
X252017Y598736D01*
X252100Y598403D01*
X252350Y598194D01*
X252642Y598069D01*
X253683D01*
G01X252642D02*
X252017Y596861D01*
G01X250667Y597361D02*
X250417Y597069D01*
X250083Y596903D01*
X249708Y596861D01*
X249375Y596903D01*
X249042Y597111D01*
X248833Y597361D01*
X248792Y597611D01*
X248875Y597903D01*
X249167Y598111D01*
X249458Y598194D01*
X249833D01*
G01X249458D02*
X249208Y598319D01*
X249000Y598528D01*
X248917Y598778D01*
X249000Y599028D01*
X249208Y599236D01*
X249583Y599361D01*
X249958Y599319D01*
X250333Y599153D01*
G01X246650Y596861D02*
X246358Y596903D01*
X246025Y597028D01*
X245817Y597236D01*
X245733Y597528D01*
X245817Y597819D01*
X246067Y598069D01*
X246442Y598194D01*
X246858D01*
X247108Y598278D01*
X247317Y598486D01*
X247400Y598778D01*
X247275Y599069D01*
X246983Y599278D01*
X246650Y599361D01*
X246317Y599278D01*
X246025Y599069D01*
X245900Y598778D01*
X245983Y598486D01*
X246192Y598278D01*
X246442Y598194D01*
X246858D01*
X247233Y598069D01*
X247483Y597819D01*
X247567Y597528D01*
X247483Y597236D01*
X247275Y597028D01*
X246942Y596903D01*
X246650Y596861D01*
G01X244467Y597361D02*
X244217Y597069D01*
X243883Y596903D01*
X243508Y596861D01*
X243175Y596903D01*
X242842Y597111D01*
X242633Y597361D01*
X242592Y597611D01*
X242675Y597903D01*
X242967Y598111D01*
X243258Y598194D01*
X243633D01*
G01X243258D02*
X243008Y598319D01*
X242800Y598528D01*
X242717Y598778D01*
X242800Y599028D01*
X243008Y599236D01*
X243383Y599361D01*
X243758Y599319D01*
X244133Y599153D01*
G01X228400Y599200D02*
Y595200D01*
X221000D01*
G01X247500Y569100D02*
Y573100D01*
X254900D01*
G01X255176Y577059D02*
X257676D01*
Y578100D01*
X257551Y578434D01*
X257384Y578642D01*
X257051Y578725D01*
X256718Y578642D01*
X256509Y578392D01*
X256384Y578100D01*
Y577059D01*
G01Y578100D02*
X255176Y578725D01*
G01X257259Y580200D02*
X257509Y580450D01*
X257634Y580742D01*
X257676Y581075D01*
X257593Y581492D01*
X257384Y581784D01*
X257134Y581867D01*
X256884Y581825D01*
X256676Y581659D01*
X256259Y580825D01*
X255968Y580450D01*
X255551Y580200D01*
X255176Y580117D01*
Y581867D01*
G01X257676Y584092D02*
X257593Y583759D01*
X257384Y583509D01*
X257134Y583342D01*
X256801Y583217D01*
X256426Y583175D01*
X256051Y583217D01*
X255718Y583342D01*
X255468Y583509D01*
X255259Y583759D01*
X255176Y584092D01*
X255259Y584425D01*
X255468Y584675D01*
X255718Y584842D01*
X256051Y584967D01*
X256426Y585009D01*
X256801Y584967D01*
X257134Y584842D01*
X257384Y584675D01*
X257593Y584425D01*
X257676Y584092D01*
G01X255176Y587192D02*
X257676D01*
X257176Y586692D01*
G01X255176D02*
Y587692D01*
G01X254300Y575300D02*
X250300D01*
Y582700D01*
G01X281200Y567717D02*
X283700D01*
Y568758D01*
X283575Y569092D01*
X283408Y569300D01*
X283075Y569383D01*
X282742Y569300D01*
X282533Y569050D01*
X282408Y568758D01*
Y567717D01*
G01Y568758D02*
X281200Y569383D01*
G01Y571650D02*
X283700D01*
X283200Y571150D01*
G01X281200D02*
Y572150D01*
G01X281492Y574042D02*
X281283Y574333D01*
X281200Y574667D01*
X281283Y575000D01*
X281533Y575292D01*
X281908Y575500D01*
X282283Y575583D01*
X282742D01*
X283117Y575500D01*
X283450Y575292D01*
X283617Y575042D01*
X283700Y574750D01*
X283617Y574417D01*
X283450Y574167D01*
X283200Y574000D01*
X282867Y573917D01*
X282575Y574000D01*
X282283Y574208D01*
X282117Y574458D01*
X282075Y574750D01*
X282158Y575083D01*
X282367Y575333D01*
X282742Y575583D01*
G01X281200Y578350D02*
X283700D01*
X281908Y576808D01*
Y578892D01*
G01X271895Y573352D02*
X275895D01*
Y565952D01*
G01X244100Y581000D02*
X240100D01*
Y588400D01*
G01X253583Y591161D02*
Y593661D01*
X252542D01*
X252208Y593536D01*
X252000Y593369D01*
X251917Y593036D01*
X252000Y592703D01*
X252250Y592494D01*
X252542Y592369D01*
X253583D01*
G01X252542D02*
X251917Y591161D01*
G01X250567Y591661D02*
X250317Y591369D01*
X249983Y591203D01*
X249608Y591161D01*
X249275Y591203D01*
X248942Y591411D01*
X248733Y591661D01*
X248692Y591911D01*
X248775Y592203D01*
X249067Y592411D01*
X249358Y592494D01*
X249733D01*
G01X249358D02*
X249108Y592619D01*
X248900Y592828D01*
X248817Y593078D01*
X248900Y593328D01*
X249108Y593536D01*
X249483Y593661D01*
X249858Y593619D01*
X250233Y593453D01*
G01X246550Y591161D02*
X246258Y591203D01*
X245925Y591328D01*
X245717Y591536D01*
X245633Y591828D01*
X245717Y592119D01*
X245967Y592369D01*
X246342Y592494D01*
X246758D01*
X247008Y592578D01*
X247217Y592786D01*
X247300Y593078D01*
X247175Y593369D01*
X246883Y593578D01*
X246550Y593661D01*
X246217Y593578D01*
X245925Y593369D01*
X245800Y593078D01*
X245883Y592786D01*
X246092Y592578D01*
X246342Y592494D01*
X246758D01*
X247133Y592369D01*
X247383Y592119D01*
X247467Y591828D01*
X247383Y591536D01*
X247175Y591328D01*
X246842Y591203D01*
X246550Y591161D01*
G01X243450D02*
X243158Y591203D01*
X242825Y591328D01*
X242617Y591536D01*
X242533Y591828D01*
X242617Y592119D01*
X242867Y592369D01*
X243242Y592494D01*
X243658D01*
X243908Y592578D01*
X244117Y592786D01*
X244200Y593078D01*
X244075Y593369D01*
X243783Y593578D01*
X243450Y593661D01*
X243117Y593578D01*
X242825Y593369D01*
X242700Y593078D01*
X242783Y592786D01*
X242992Y592578D01*
X243242Y592494D01*
X243658D01*
X244033Y592369D01*
X244283Y592119D01*
X244367Y591828D01*
X244283Y591536D01*
X244075Y591328D01*
X243742Y591203D01*
X243450Y591161D01*
G01X228400Y595200D02*
Y591200D01*
X221000D01*
G01X277086Y580269D02*
X279586D01*
Y581310D01*
X279461Y581644D01*
X279294Y581852D01*
X278961Y581935D01*
X278628Y581852D01*
X278419Y581602D01*
X278294Y581310D01*
Y580269D01*
G01Y581310D02*
X277086Y581935D01*
G01X277586Y583285D02*
X277294Y583535D01*
X277128Y583869D01*
X277086Y584244D01*
X277128Y584577D01*
X277336Y584910D01*
X277586Y585119D01*
X277836Y585160D01*
X278128Y585077D01*
X278336Y584785D01*
X278419Y584494D01*
Y584119D01*
G01Y584494D02*
X278544Y584744D01*
X278753Y584952D01*
X279003Y585035D01*
X279253Y584952D01*
X279461Y584744D01*
X279586Y584369D01*
X279544Y583994D01*
X279378Y583619D01*
G01X277086Y587302D02*
X277128Y587594D01*
X277253Y587927D01*
X277461Y588135D01*
X277753Y588219D01*
X278044Y588135D01*
X278294Y587885D01*
X278419Y587510D01*
Y587094D01*
X278503Y586844D01*
X278711Y586635D01*
X279003Y586552D01*
X279294Y586677D01*
X279503Y586969D01*
X279586Y587302D01*
X279503Y587635D01*
X279294Y587927D01*
X279003Y588052D01*
X278711Y587969D01*
X278503Y587760D01*
X278419Y587510D01*
Y587094D01*
X278294Y586719D01*
X278044Y586469D01*
X277753Y586385D01*
X277461Y586469D01*
X277253Y586677D01*
X277128Y587010D01*
X277086Y587302D01*
G01Y590402D02*
X279586D01*
X279086Y589902D01*
G01X277086D02*
Y590902D01*
G01X270900Y589700D02*
X274900D01*
Y582300D01*
G01X229400Y573900D02*
Y569900D01*
X222000D01*
G01X229775Y578816D02*
Y574816D01*
X222375D01*
G01X229700Y587900D02*
Y583900D01*
X222300D01*
G01X279983Y592161D02*
Y594661D01*
X278942D01*
X278608Y594536D01*
X278400Y594369D01*
X278317Y594036D01*
X278400Y593703D01*
X278650Y593494D01*
X278942Y593369D01*
X279983D01*
G01X278942D02*
X278317Y592161D01*
G01X276967Y592661D02*
X276717Y592369D01*
X276383Y592203D01*
X276008Y592161D01*
X275675Y592203D01*
X275342Y592411D01*
X275133Y592661D01*
X275092Y592911D01*
X275175Y593203D01*
X275467Y593411D01*
X275758Y593494D01*
X276133D01*
G01X275758D02*
X275508Y593619D01*
X275300Y593828D01*
X275217Y594078D01*
X275300Y594328D01*
X275508Y594536D01*
X275883Y594661D01*
X276258Y594619D01*
X276633Y594453D01*
G01X273867Y592661D02*
X273617Y592369D01*
X273283Y592203D01*
X272908Y592161D01*
X272575Y592203D01*
X272242Y592411D01*
X272033Y592661D01*
X271992Y592911D01*
X272075Y593203D01*
X272367Y593411D01*
X272658Y593494D01*
X273033D01*
G01X272658D02*
X272408Y593619D01*
X272200Y593828D01*
X272117Y594078D01*
X272200Y594328D01*
X272408Y594536D01*
X272783Y594661D01*
X273158Y594619D01*
X273533Y594453D01*
G01X269350Y592161D02*
Y594661D01*
X270892Y592869D01*
X268808D01*
G01X270700Y586500D02*
Y582500D01*
X263300D01*
G01X239730Y569032D02*
Y573032D01*
X247130D01*
G01X240600Y580500D02*
X244600D01*
Y573100D01*
G01X277200Y567717D02*
X279700D01*
Y568758D01*
X279575Y569092D01*
X279408Y569300D01*
X279075Y569383D01*
X278742Y569300D01*
X278533Y569050D01*
X278408Y568758D01*
Y567717D01*
G01Y568758D02*
X277200Y569383D01*
G01Y571650D02*
X279700D01*
X279200Y571150D01*
G01X277200D02*
Y572150D01*
G01X278242Y573958D02*
X278533Y574250D01*
X278700Y574500D01*
X278783Y574833D01*
X278700Y575125D01*
X278533Y575333D01*
X278283Y575500D01*
X277992Y575542D01*
X277742Y575500D01*
X277492Y575333D01*
X277283Y575083D01*
X277200Y574792D01*
X277283Y574458D01*
X277533Y574167D01*
X277908Y574000D01*
X278325Y573958D01*
X278867Y574042D01*
X279158Y574167D01*
X279450Y574375D01*
X279658Y574667D01*
X279700Y574958D01*
X279617Y575250D01*
X279408Y575458D01*
G01X277200Y577850D02*
X279700D01*
X279200Y577350D01*
G01X277200D02*
Y578350D01*
G01X267806Y573352D02*
X271806D01*
Y565952D01*
G01X291904Y590967D02*
Y593467D01*
X290863D01*
X290529Y593342D01*
X290321Y593175D01*
X290238Y592842D01*
X290321Y592509D01*
X290571Y592300D01*
X290863Y592175D01*
X291904D01*
G01X290863D02*
X290238Y590967D01*
G01X288888Y591342D02*
X288638Y591134D01*
X288346Y591009D01*
X287971Y590967D01*
X287596Y591050D01*
X287304Y591217D01*
X287096Y591509D01*
X287054Y591842D01*
X287138Y592175D01*
X287346Y592384D01*
X287638Y592550D01*
X287929Y592592D01*
X288221Y592550D01*
X288596Y592384D01*
X288471Y593467D01*
X287346D01*
G01X284871D02*
X285204Y593384D01*
X285454Y593175D01*
X285621Y592925D01*
X285746Y592592D01*
X285788Y592217D01*
X285746Y591842D01*
X285621Y591509D01*
X285454Y591259D01*
X285204Y591050D01*
X284871Y590967D01*
X284538Y591050D01*
X284288Y591259D01*
X284121Y591509D01*
X283996Y591842D01*
X283954Y592217D01*
X283996Y592592D01*
X284121Y592925D01*
X284288Y593175D01*
X284538Y593384D01*
X284871Y593467D01*
G01X255172Y635057D02*
X255297Y634807D01*
X255380Y634515D01*
Y634182D01*
X255255Y633807D01*
X255047Y633515D01*
X254797Y633307D01*
X254380Y633140D01*
X254005Y633098D01*
X253630Y633182D01*
X253380Y633307D01*
X253130Y633557D01*
X252963Y633848D01*
X252880Y634140D01*
Y634432D01*
X252963Y634723D01*
X253088Y634973D01*
X253255Y635182D01*
G01X252880Y637240D02*
X252922Y637532D01*
X253047Y637865D01*
X253255Y638073D01*
X253547Y638157D01*
X253838Y638073D01*
X254088Y637823D01*
X254213Y637448D01*
Y637032D01*
X254297Y636782D01*
X254505Y636573D01*
X254797Y636490D01*
X255088Y636615D01*
X255297Y636907D01*
X255380Y637240D01*
X255297Y637573D01*
X255088Y637865D01*
X254797Y637990D01*
X254505Y637907D01*
X254297Y637698D01*
X254213Y637448D01*
Y637032D01*
X254088Y636657D01*
X253838Y636407D01*
X253547Y636323D01*
X253255Y636407D01*
X253047Y636615D01*
X252922Y636948D01*
X252880Y637240D01*
G01Y640257D02*
X253422Y640340D01*
X253880Y640465D01*
X254297Y640632D01*
X254755Y640840D01*
X255380Y641173D01*
Y639507D01*
G01X256787Y619634D02*
X254287D01*
Y621300D01*
G01X256370Y622775D02*
X256620Y623025D01*
X256745Y623317D01*
X256787Y623650D01*
X256704Y624067D01*
X256495Y624359D01*
X256245Y624442D01*
X255995Y624400D01*
X255787Y624234D01*
X255370Y623400D01*
X255079Y623025D01*
X254662Y622775D01*
X254287Y622692D01*
Y624442D01*
G01X238300Y613500D02*
X245300D01*
Y626900D01*
X238300D01*
Y613500D01*
G01X242675Y652294D02*
X242925Y652419D01*
X243217Y652502D01*
X243550D01*
X243925Y652377D01*
X244217Y652169D01*
X244425Y651919D01*
X244592Y651502D01*
X244634Y651127D01*
X244550Y650752D01*
X244425Y650502D01*
X244175Y650252D01*
X243884Y650085D01*
X243592Y650002D01*
X243300D01*
X243009Y650085D01*
X242759Y650210D01*
X242550Y650377D01*
G01X240492Y650002D02*
Y652502D01*
X240992Y652002D01*
G01Y650002D02*
X239992D01*
G01X238184Y652085D02*
X237934Y652335D01*
X237642Y652460D01*
X237309Y652502D01*
X236892Y652419D01*
X236600Y652210D01*
X236517Y651960D01*
X236559Y651710D01*
X236725Y651502D01*
X237559Y651085D01*
X237934Y650794D01*
X238184Y650377D01*
X238267Y650002D01*
X236517D01*
G01X235209Y650502D02*
X234959Y650210D01*
X234625Y650044D01*
X234250Y650002D01*
X233917Y650044D01*
X233584Y650252D01*
X233375Y650502D01*
X233334Y650752D01*
X233417Y651044D01*
X233709Y651252D01*
X234000Y651335D01*
X234375D01*
G01X234000D02*
X233750Y651460D01*
X233542Y651669D01*
X233459Y651919D01*
X233542Y652169D01*
X233750Y652377D01*
X234125Y652502D01*
X234500Y652460D01*
X234875Y652294D01*
G01X228646Y656458D02*
X228896Y656583D01*
X229188Y656666D01*
X229521D01*
X229896Y656541D01*
X230188Y656333D01*
X230396Y656083D01*
X230563Y655666D01*
X230605Y655291D01*
X230521Y654916D01*
X230396Y654666D01*
X230146Y654416D01*
X229855Y654249D01*
X229563Y654166D01*
X229271D01*
X228980Y654249D01*
X228730Y654374D01*
X228521Y654541D01*
G01X226463Y654166D02*
Y656666D01*
X226963Y656166D01*
G01Y654166D02*
X225963D01*
G01X223363D02*
Y656666D01*
X223863Y656166D01*
G01Y654166D02*
X222863D01*
G01X220346D02*
X220263Y654708D01*
X220138Y655166D01*
X219971Y655583D01*
X219763Y656041D01*
X219430Y656666D01*
X221096D01*
G01X257433Y665000D02*
Y667500D01*
X256392D01*
X256058Y667375D01*
X255850Y667208D01*
X255767Y666875D01*
X255850Y666542D01*
X256100Y666333D01*
X256392Y666208D01*
X257433D01*
G01X256392D02*
X255767Y665000D01*
G01X253583D02*
X253500Y665542D01*
X253375Y666000D01*
X253208Y666417D01*
X253000Y666875D01*
X252667Y667500D01*
X254333D01*
G01X251108Y665292D02*
X250817Y665083D01*
X250483Y665000D01*
X250150Y665083D01*
X249858Y665333D01*
X249650Y665708D01*
X249567Y666083D01*
Y666542D01*
X249650Y666917D01*
X249858Y667250D01*
X250108Y667417D01*
X250400Y667500D01*
X250733Y667417D01*
X250983Y667250D01*
X251150Y667000D01*
X251233Y666667D01*
X251150Y666375D01*
X250942Y666083D01*
X250692Y665917D01*
X250400Y665875D01*
X250067Y665958D01*
X249817Y666167D01*
X249567Y666542D01*
G01X268688Y668467D02*
Y664467D01*
X261288D01*
G01X230396Y658166D02*
Y660666D01*
X229355D01*
X229021Y660541D01*
X228813Y660374D01*
X228730Y660041D01*
X228813Y659708D01*
X229063Y659499D01*
X229355Y659374D01*
X230396D01*
G01X229355D02*
X228730Y658166D01*
G01X225963D02*
Y660666D01*
X227505Y658874D01*
X225421D01*
G01X223363Y660666D02*
X223696Y660583D01*
X223946Y660374D01*
X224113Y660124D01*
X224238Y659791D01*
X224280Y659416D01*
X224238Y659041D01*
X224113Y658708D01*
X223946Y658458D01*
X223696Y658249D01*
X223363Y658166D01*
X223030Y658249D01*
X222780Y658458D01*
X222613Y658708D01*
X222488Y659041D01*
X222446Y659416D01*
X222488Y659791D01*
X222613Y660124D01*
X222780Y660374D01*
X223030Y660583D01*
X223363Y660666D01*
G01X220263Y658166D02*
Y660666D01*
X220763Y660166D01*
G01Y658166D02*
X219763D01*
G01X244425Y658002D02*
Y660502D01*
X243384D01*
X243050Y660377D01*
X242842Y660210D01*
X242759Y659877D01*
X242842Y659544D01*
X243092Y659335D01*
X243384Y659210D01*
X244425D01*
G01X243384D02*
X242759Y658002D01*
G01X239992D02*
Y660502D01*
X241534Y658710D01*
X239450D01*
G01X237392Y658002D02*
Y660502D01*
X237892Y660002D01*
G01Y658002D02*
X236892D01*
G01X235209Y658502D02*
X234959Y658210D01*
X234625Y658044D01*
X234250Y658002D01*
X233917Y658044D01*
X233584Y658252D01*
X233375Y658502D01*
X233334Y658752D01*
X233417Y659044D01*
X233709Y659252D01*
X234000Y659335D01*
X234375D01*
G01X234000D02*
X233750Y659460D01*
X233542Y659669D01*
X233459Y659919D01*
X233542Y660169D01*
X233750Y660377D01*
X234125Y660502D01*
X234500Y660460D01*
X234875Y660294D01*
G01X227492Y644006D02*
Y640006D01*
X220092D01*
G01X244425Y654002D02*
Y656502D01*
X243384D01*
X243050Y656377D01*
X242842Y656210D01*
X242759Y655877D01*
X242842Y655544D01*
X243092Y655335D01*
X243384Y655210D01*
X244425D01*
G01X243384D02*
X242759Y654002D01*
G01X239992D02*
Y656502D01*
X241534Y654710D01*
X239450D01*
G01X237392Y654002D02*
Y656502D01*
X237892Y656002D01*
G01Y654002D02*
X236892D01*
G01X235209Y654377D02*
X234959Y654169D01*
X234667Y654044D01*
X234292Y654002D01*
X233917Y654085D01*
X233625Y654252D01*
X233417Y654544D01*
X233375Y654877D01*
X233459Y655210D01*
X233667Y655419D01*
X233959Y655585D01*
X234250Y655627D01*
X234542Y655585D01*
X234917Y655419D01*
X234792Y656502D01*
X233667D01*
G01X230396Y650166D02*
Y652666D01*
X229355D01*
X229021Y652541D01*
X228813Y652374D01*
X228730Y652041D01*
X228813Y651708D01*
X229063Y651499D01*
X229355Y651374D01*
X230396D01*
G01X229355D02*
X228730Y650166D01*
G01X225963D02*
Y652666D01*
X227505Y650874D01*
X225421D01*
G01X223363Y652666D02*
X223696Y652583D01*
X223946Y652374D01*
X224113Y652124D01*
X224238Y651791D01*
X224280Y651416D01*
X224238Y651041D01*
X224113Y650708D01*
X223946Y650458D01*
X223696Y650249D01*
X223363Y650166D01*
X223030Y650249D01*
X222780Y650458D01*
X222613Y650708D01*
X222488Y651041D01*
X222446Y651416D01*
X222488Y651791D01*
X222613Y652124D01*
X222780Y652374D01*
X223030Y652583D01*
X223363Y652666D01*
G01X219763Y650166D02*
Y652666D01*
X221305Y650874D01*
X219221D01*
G01X362075Y28402D02*
X362325Y28527D01*
X362617Y28610D01*
X362950D01*
X363325Y28485D01*
X363617Y28277D01*
X363825Y28027D01*
X363992Y27610D01*
X364034Y27235D01*
X363950Y26860D01*
X363825Y26610D01*
X363575Y26360D01*
X363284Y26193D01*
X362992Y26110D01*
X362700D01*
X362409Y26193D01*
X362159Y26318D01*
X361950Y26485D01*
G01X360809D02*
X360559Y26277D01*
X360267Y26152D01*
X359892Y26110D01*
X359517Y26193D01*
X359225Y26360D01*
X359017Y26652D01*
X358975Y26985D01*
X359059Y27318D01*
X359267Y27527D01*
X359559Y27693D01*
X359850Y27735D01*
X360142Y27693D01*
X360517Y27527D01*
X360392Y28610D01*
X359267D01*
G01X357584Y28193D02*
X357334Y28443D01*
X357042Y28568D01*
X356709Y28610D01*
X356292Y28527D01*
X356000Y28318D01*
X355917Y28068D01*
X355959Y27818D01*
X356125Y27610D01*
X356959Y27193D01*
X357334Y26902D01*
X357584Y26485D01*
X357667Y26110D01*
X355917D01*
G01X354609Y26485D02*
X354359Y26277D01*
X354067Y26152D01*
X353692Y26110D01*
X353317Y26193D01*
X353025Y26360D01*
X352817Y26652D01*
X352775Y26985D01*
X352859Y27318D01*
X353067Y27527D01*
X353359Y27693D01*
X353650Y27735D01*
X353942Y27693D01*
X354317Y27527D01*
X354192Y28610D01*
X353067D01*
G01X336433Y177150D02*
X336683Y177275D01*
X336975Y177358D01*
X337308D01*
X337683Y177233D01*
X337975Y177025D01*
X338183Y176775D01*
X338350Y176358D01*
X338392Y175983D01*
X338308Y175608D01*
X338183Y175358D01*
X337933Y175108D01*
X337642Y174941D01*
X337350Y174858D01*
X337058D01*
X336767Y174941D01*
X336517Y175066D01*
X336308Y175233D01*
G01X335167D02*
X334917Y175025D01*
X334625Y174900D01*
X334250Y174858D01*
X333875Y174941D01*
X333583Y175108D01*
X333375Y175400D01*
X333333Y175733D01*
X333417Y176066D01*
X333625Y176275D01*
X333917Y176441D01*
X334208Y176483D01*
X334500Y176441D01*
X334875Y176275D01*
X334750Y177358D01*
X333625D01*
G01X331150Y174858D02*
Y177358D01*
X331650Y176858D01*
G01Y174858D02*
X330650D01*
G01X328050D02*
Y177358D01*
X328550Y176858D01*
G01Y174858D02*
X327550D01*
G01X314565Y208770D02*
X314815Y208895D01*
X315107Y208978D01*
X315440D01*
X315815Y208853D01*
X316107Y208645D01*
X316315Y208395D01*
X316482Y207978D01*
X316524Y207603D01*
X316440Y207228D01*
X316315Y206978D01*
X316065Y206728D01*
X315774Y206561D01*
X315482Y206478D01*
X315190D01*
X314899Y206561D01*
X314649Y206686D01*
X314440Y206853D01*
G01X313174Y208561D02*
X312924Y208811D01*
X312632Y208936D01*
X312299Y208978D01*
X311882Y208895D01*
X311590Y208686D01*
X311507Y208436D01*
X311549Y208186D01*
X311715Y207978D01*
X312549Y207561D01*
X312924Y207270D01*
X313174Y206853D01*
X313257Y206478D01*
X311507D01*
G01X309282D02*
X308990Y206520D01*
X308657Y206645D01*
X308449Y206853D01*
X308365Y207145D01*
X308449Y207436D01*
X308699Y207686D01*
X309074Y207811D01*
X309490D01*
X309740Y207895D01*
X309949Y208103D01*
X310032Y208395D01*
X309907Y208686D01*
X309615Y208895D01*
X309282Y208978D01*
X308949Y208895D01*
X308657Y208686D01*
X308532Y208395D01*
X308615Y208103D01*
X308824Y207895D01*
X309074Y207811D01*
X309490D01*
X309865Y207686D01*
X310115Y207436D01*
X310199Y207145D01*
X310115Y206853D01*
X309907Y206645D01*
X309574Y206520D01*
X309282Y206478D01*
G01X336515Y181350D02*
X336765Y181475D01*
X337057Y181558D01*
X337390D01*
X337765Y181433D01*
X338057Y181225D01*
X338265Y180975D01*
X338432Y180558D01*
X338474Y180183D01*
X338390Y179808D01*
X338265Y179558D01*
X338015Y179308D01*
X337724Y179141D01*
X337432Y179058D01*
X337140D01*
X336849Y179141D01*
X336599Y179266D01*
X336390Y179433D01*
G01X335124Y181141D02*
X334874Y181391D01*
X334582Y181516D01*
X334249Y181558D01*
X333832Y181475D01*
X333540Y181266D01*
X333457Y181016D01*
X333499Y180766D01*
X333665Y180558D01*
X334499Y180141D01*
X334874Y179850D01*
X335124Y179433D01*
X335207Y179058D01*
X333457D01*
G01X332149Y179433D02*
X331899Y179225D01*
X331607Y179100D01*
X331232Y179058D01*
X330857Y179141D01*
X330565Y179308D01*
X330357Y179600D01*
X330315Y179933D01*
X330399Y180266D01*
X330607Y180475D01*
X330899Y180641D01*
X331190Y180683D01*
X331482Y180641D01*
X331857Y180475D01*
X331732Y181558D01*
X330607D01*
G01X316692Y234367D02*
X316817Y234117D01*
X316900Y233825D01*
Y233492D01*
X316775Y233117D01*
X316567Y232825D01*
X316317Y232617D01*
X315900Y232450D01*
X315525Y232408D01*
X315150Y232492D01*
X314900Y232617D01*
X314650Y232867D01*
X314483Y233158D01*
X314400Y233450D01*
Y233742D01*
X314483Y234033D01*
X314608Y234283D01*
X314775Y234492D01*
G01X314400Y236550D02*
X316900D01*
X316400Y236050D01*
G01X314400D02*
Y237050D01*
G01Y239650D02*
X314442Y239942D01*
X314567Y240275D01*
X314775Y240483D01*
X315067Y240567D01*
X315358Y240483D01*
X315608Y240233D01*
X315733Y239858D01*
Y239442D01*
X315817Y239192D01*
X316025Y238983D01*
X316317Y238900D01*
X316608Y239025D01*
X316817Y239317D01*
X316900Y239650D01*
X316817Y239983D01*
X316608Y240275D01*
X316317Y240400D01*
X316025Y240317D01*
X315817Y240108D01*
X315733Y239858D01*
Y239442D01*
X315608Y239067D01*
X315358Y238817D01*
X315067Y238733D01*
X314775Y238817D01*
X314567Y239025D01*
X314442Y239358D01*
X314400Y239650D01*
G01Y242667D02*
X314942Y242750D01*
X315400Y242875D01*
X315817Y243042D01*
X316275Y243250D01*
X316900Y243583D01*
Y241917D01*
G01X310192Y234367D02*
X310317Y234117D01*
X310400Y233825D01*
Y233492D01*
X310275Y233117D01*
X310067Y232825D01*
X309817Y232617D01*
X309400Y232450D01*
X309025Y232408D01*
X308650Y232492D01*
X308400Y232617D01*
X308150Y232867D01*
X307983Y233158D01*
X307900Y233450D01*
Y233742D01*
X307983Y234033D01*
X308108Y234283D01*
X308275Y234492D01*
G01X307900Y236550D02*
X310400D01*
X309900Y236050D01*
G01X307900D02*
Y237050D01*
G01Y239650D02*
X307942Y239942D01*
X308067Y240275D01*
X308275Y240483D01*
X308567Y240567D01*
X308858Y240483D01*
X309108Y240233D01*
X309233Y239858D01*
Y239442D01*
X309317Y239192D01*
X309525Y238983D01*
X309817Y238900D01*
X310108Y239025D01*
X310317Y239317D01*
X310400Y239650D01*
X310317Y239983D01*
X310108Y240275D01*
X309817Y240400D01*
X309525Y240317D01*
X309317Y240108D01*
X309233Y239858D01*
Y239442D01*
X309108Y239067D01*
X308858Y238817D01*
X308567Y238733D01*
X308275Y238817D01*
X308067Y239025D01*
X307942Y239358D01*
X307900Y239650D01*
G01Y242750D02*
X307942Y243042D01*
X308067Y243375D01*
X308275Y243583D01*
X308567Y243667D01*
X308858Y243583D01*
X309108Y243333D01*
X309233Y242958D01*
Y242542D01*
X309317Y242292D01*
X309525Y242083D01*
X309817Y242000D01*
X310108Y242125D01*
X310317Y242417D01*
X310400Y242750D01*
X310317Y243083D01*
X310108Y243375D01*
X309817Y243500D01*
X309525Y243417D01*
X309317Y243208D01*
X309233Y242958D01*
Y242542D01*
X309108Y242167D01*
X308858Y241917D01*
X308567Y241833D01*
X308275Y241917D01*
X308067Y242125D01*
X307942Y242458D01*
X307900Y242750D01*
G01X341311Y217692D02*
X341436Y217442D01*
X341519Y217150D01*
Y216817D01*
X341394Y216442D01*
X341186Y216150D01*
X340936Y215942D01*
X340519Y215775D01*
X340144Y215733D01*
X339769Y215817D01*
X339519Y215942D01*
X339269Y216192D01*
X339102Y216483D01*
X339019Y216775D01*
Y217067D01*
X339102Y217358D01*
X339227Y217608D01*
X339394Y217817D01*
G01Y218958D02*
X339186Y219208D01*
X339061Y219500D01*
X339019Y219875D01*
X339102Y220250D01*
X339269Y220542D01*
X339561Y220750D01*
X339894Y220792D01*
X340227Y220708D01*
X340436Y220500D01*
X340602Y220208D01*
X340644Y219917D01*
X340602Y219625D01*
X340436Y219250D01*
X341519Y219375D01*
Y220500D01*
G01X339019Y222975D02*
X341519D01*
X341019Y222475D01*
G01X339019D02*
Y223475D01*
G01X341102Y225283D02*
X341352Y225533D01*
X341477Y225825D01*
X341519Y226158D01*
X341436Y226575D01*
X341227Y226867D01*
X340977Y226950D01*
X340727Y226908D01*
X340519Y226742D01*
X340102Y225908D01*
X339811Y225533D01*
X339394Y225283D01*
X339019Y225200D01*
Y226950D01*
G01X325620Y243964D02*
X325870Y244089D01*
X326162Y244172D01*
X326495D01*
X326870Y244047D01*
X327162Y243839D01*
X327370Y243589D01*
X327537Y243172D01*
X327579Y242797D01*
X327495Y242422D01*
X327370Y242172D01*
X327120Y241922D01*
X326829Y241755D01*
X326537Y241672D01*
X326245D01*
X325954Y241755D01*
X325704Y241880D01*
X325495Y242047D01*
G01X324229Y243755D02*
X323979Y244005D01*
X323687Y244130D01*
X323354Y244172D01*
X322937Y244089D01*
X322645Y243880D01*
X322562Y243630D01*
X322604Y243380D01*
X322770Y243172D01*
X323604Y242755D01*
X323979Y242464D01*
X324229Y242047D01*
X324312Y241672D01*
X322562D01*
G01X321045Y241964D02*
X320754Y241755D01*
X320420Y241672D01*
X320087Y241755D01*
X319795Y242005D01*
X319587Y242380D01*
X319504Y242755D01*
Y243214D01*
X319587Y243589D01*
X319795Y243922D01*
X320045Y244089D01*
X320337Y244172D01*
X320670Y244089D01*
X320920Y243922D01*
X321087Y243672D01*
X321170Y243339D01*
X321087Y243047D01*
X320879Y242755D01*
X320629Y242589D01*
X320337Y242547D01*
X320004Y242630D01*
X319754Y242839D01*
X319504Y243214D01*
G01X327600Y390417D02*
Y392917D01*
X326559D01*
X326225Y392792D01*
X326017Y392625D01*
X325934Y392292D01*
X326017Y391959D01*
X326267Y391750D01*
X326559Y391625D01*
X327600D01*
G01X326559D02*
X325934Y390417D01*
G01X324459Y391459D02*
X324167Y391750D01*
X323917Y391917D01*
X323584Y392000D01*
X323292Y391917D01*
X323084Y391750D01*
X322917Y391500D01*
X322875Y391209D01*
X322917Y390959D01*
X323084Y390709D01*
X323334Y390500D01*
X323625Y390417D01*
X323959Y390500D01*
X324250Y390750D01*
X324417Y391125D01*
X324459Y391542D01*
X324375Y392084D01*
X324250Y392375D01*
X324042Y392667D01*
X323750Y392875D01*
X323459Y392917D01*
X323167Y392834D01*
X322959Y392625D01*
G01X320067Y390417D02*
Y392917D01*
X321609Y391125D01*
X319525D01*
G01X333500Y389774D02*
Y385774D01*
X326100D01*
G01X360683Y374633D02*
Y377133D01*
X359642D01*
X359308Y377008D01*
X359100Y376841D01*
X359017Y376508D01*
X359100Y376175D01*
X359350Y375966D01*
X359642Y375841D01*
X360683D01*
G01X359642D02*
X359017Y374633D01*
G01X356833D02*
X356750Y375175D01*
X356625Y375633D01*
X356458Y376050D01*
X356250Y376508D01*
X355917Y377133D01*
X357583D01*
G01X354442Y376716D02*
X354192Y376966D01*
X353900Y377091D01*
X353567Y377133D01*
X353150Y377050D01*
X352858Y376841D01*
X352775Y376591D01*
X352817Y376341D01*
X352983Y376133D01*
X353817Y375716D01*
X354192Y375425D01*
X354442Y375008D01*
X354525Y374633D01*
X352775D01*
G01X350550D02*
X350258Y374675D01*
X349925Y374800D01*
X349717Y375008D01*
X349633Y375300D01*
X349717Y375591D01*
X349967Y375841D01*
X350342Y375966D01*
X350758D01*
X351008Y376050D01*
X351217Y376258D01*
X351300Y376550D01*
X351175Y376841D01*
X350883Y377050D01*
X350550Y377133D01*
X350217Y377050D01*
X349925Y376841D01*
X349800Y376550D01*
X349883Y376258D01*
X350092Y376050D01*
X350342Y375966D01*
X350758D01*
X351133Y375841D01*
X351383Y375591D01*
X351467Y375300D01*
X351383Y375008D01*
X351175Y374800D01*
X350842Y374675D01*
X350550Y374633D01*
G01X347600Y379800D02*
Y375800D01*
X340200D01*
G01X343231Y397241D02*
X343564Y397283D01*
X343856Y397449D01*
X344106Y397699D01*
X344273Y397991D01*
X344356Y398324D01*
Y398658D01*
X344273Y398991D01*
X344106Y399283D01*
X343856Y399533D01*
X343564Y399699D01*
X343231Y399741D01*
X342898Y399699D01*
X342606Y399533D01*
X342356Y399283D01*
X342189Y398991D01*
X342106Y398658D01*
Y398324D01*
X342189Y397991D01*
X342356Y397699D01*
X342606Y397449D01*
X342898Y397283D01*
X343231Y397241D01*
G01X342898Y397908D02*
X342398Y397241D01*
G01X340923Y399324D02*
X340673Y399574D01*
X340381Y399699D01*
X340048Y399741D01*
X339631Y399658D01*
X339339Y399449D01*
X339256Y399199D01*
X339298Y398949D01*
X339464Y398741D01*
X340298Y398324D01*
X340673Y398033D01*
X340923Y397616D01*
X341006Y397241D01*
X339256D01*
G01X337948Y397616D02*
X337698Y397408D01*
X337406Y397283D01*
X337031Y397241D01*
X336656Y397324D01*
X336364Y397491D01*
X336156Y397783D01*
X336114Y398116D01*
X336198Y398449D01*
X336406Y398658D01*
X336698Y398824D01*
X336989Y398866D01*
X337281Y398824D01*
X337656Y398658D01*
X337531Y399741D01*
X336406D01*
G01X334131Y381574D02*
Y395574D01*
G01X347131Y381574D02*
X334131D01*
G01X347131Y395574D02*
Y381574D01*
G01X334131Y395574D02*
X347131D01*
G01X351792Y524767D02*
X351917Y524517D01*
X352000Y524225D01*
Y523892D01*
X351875Y523517D01*
X351667Y523225D01*
X351417Y523017D01*
X351000Y522850D01*
X350625Y522808D01*
X350250Y522892D01*
X350000Y523017D01*
X349750Y523267D01*
X349583Y523558D01*
X349500Y523850D01*
Y524142D01*
X349583Y524433D01*
X349708Y524683D01*
X349875Y524892D01*
G01Y526033D02*
X349667Y526283D01*
X349542Y526575D01*
X349500Y526950D01*
X349583Y527325D01*
X349750Y527617D01*
X350042Y527825D01*
X350375Y527867D01*
X350708Y527783D01*
X350917Y527575D01*
X351083Y527283D01*
X351125Y526992D01*
X351083Y526700D01*
X350917Y526325D01*
X352000Y526450D01*
Y527575D01*
G01Y530050D02*
X351917Y529717D01*
X351708Y529467D01*
X351458Y529300D01*
X351125Y529175D01*
X350750Y529133D01*
X350375Y529175D01*
X350042Y529300D01*
X349792Y529467D01*
X349583Y529717D01*
X349500Y530050D01*
X349583Y530383D01*
X349792Y530633D01*
X350042Y530800D01*
X350375Y530925D01*
X350750Y530967D01*
X351125Y530925D01*
X351458Y530800D01*
X351708Y530633D01*
X351917Y530383D01*
X352000Y530050D01*
G01X350000Y532233D02*
X349708Y532483D01*
X349542Y532817D01*
X349500Y533192D01*
X349542Y533525D01*
X349750Y533858D01*
X350000Y534067D01*
X350250Y534108D01*
X350542Y534025D01*
X350750Y533733D01*
X350833Y533442D01*
Y533067D01*
G01Y533442D02*
X350958Y533692D01*
X351167Y533900D01*
X351417Y533983D01*
X351667Y533900D01*
X351875Y533692D01*
X352000Y533317D01*
X351958Y532942D01*
X351792Y532567D01*
G01X305959Y506767D02*
X306084Y506517D01*
X306167Y506225D01*
Y505892D01*
X306042Y505517D01*
X305834Y505225D01*
X305584Y505017D01*
X305167Y504850D01*
X304792Y504808D01*
X304417Y504892D01*
X304167Y505017D01*
X303917Y505267D01*
X303750Y505558D01*
X303667Y505850D01*
Y506142D01*
X303750Y506433D01*
X303875Y506683D01*
X304042Y506892D01*
G01Y508033D02*
X303834Y508283D01*
X303709Y508575D01*
X303667Y508950D01*
X303750Y509325D01*
X303917Y509617D01*
X304209Y509825D01*
X304542Y509867D01*
X304875Y509783D01*
X305084Y509575D01*
X305250Y509283D01*
X305292Y508992D01*
X305250Y508700D01*
X305084Y508325D01*
X306167Y508450D01*
Y509575D01*
G01Y512050D02*
X306084Y511717D01*
X305875Y511467D01*
X305625Y511300D01*
X305292Y511175D01*
X304917Y511133D01*
X304542Y511175D01*
X304209Y511300D01*
X303959Y511467D01*
X303750Y511717D01*
X303667Y512050D01*
X303750Y512383D01*
X303959Y512633D01*
X304209Y512800D01*
X304542Y512925D01*
X304917Y512967D01*
X305292Y512925D01*
X305625Y512800D01*
X305875Y512633D01*
X306084Y512383D01*
X306167Y512050D01*
G01X305750Y514358D02*
X306000Y514608D01*
X306125Y514900D01*
X306167Y515233D01*
X306084Y515650D01*
X305875Y515942D01*
X305625Y516025D01*
X305375Y515983D01*
X305167Y515817D01*
X304750Y514983D01*
X304459Y514608D01*
X304042Y514358D01*
X303667Y514275D01*
Y516025D01*
G01X301683Y533292D02*
X301933Y533417D01*
X302225Y533500D01*
X302558D01*
X302933Y533375D01*
X303225Y533167D01*
X303433Y532917D01*
X303600Y532500D01*
X303642Y532125D01*
X303558Y531750D01*
X303433Y531500D01*
X303183Y531250D01*
X302892Y531083D01*
X302600Y531000D01*
X302308D01*
X302017Y531083D01*
X301767Y531208D01*
X301558Y531375D01*
G01X300417Y531500D02*
X300167Y531208D01*
X299833Y531042D01*
X299458Y531000D01*
X299125Y531042D01*
X298792Y531250D01*
X298583Y531500D01*
X298542Y531750D01*
X298625Y532042D01*
X298917Y532250D01*
X299208Y532333D01*
X299583D01*
G01X299208D02*
X298958Y532458D01*
X298750Y532667D01*
X298667Y532917D01*
X298750Y533167D01*
X298958Y533375D01*
X299333Y533500D01*
X299708Y533458D01*
X300083Y533292D01*
G01X296400Y533500D02*
X296733Y533417D01*
X296983Y533208D01*
X297150Y532958D01*
X297275Y532625D01*
X297317Y532250D01*
X297275Y531875D01*
X297150Y531542D01*
X296983Y531292D01*
X296733Y531083D01*
X296400Y531000D01*
X296067Y531083D01*
X295817Y531292D01*
X295650Y531542D01*
X295525Y531875D01*
X295483Y532250D01*
X295525Y532625D01*
X295650Y532958D01*
X295817Y533208D01*
X296067Y533417D01*
X296400Y533500D01*
G01X359500Y561500D02*
X355500D01*
Y568900D01*
G01X352000Y543517D02*
X354500D01*
Y544558D01*
X354375Y544892D01*
X354208Y545100D01*
X353875Y545183D01*
X353542Y545100D01*
X353333Y544850D01*
X353208Y544558D01*
Y543517D01*
G01Y544558D02*
X352000Y545183D01*
G01Y547367D02*
X352542Y547450D01*
X353000Y547575D01*
X353417Y547742D01*
X353875Y547950D01*
X354500Y548283D01*
Y546617D01*
G01X354083Y549758D02*
X354333Y550008D01*
X354458Y550300D01*
X354500Y550633D01*
X354417Y551050D01*
X354208Y551342D01*
X353958Y551425D01*
X353708Y551383D01*
X353500Y551217D01*
X353083Y550383D01*
X352792Y550008D01*
X352375Y549758D01*
X352000Y549675D01*
Y551425D01*
G01Y553650D02*
X354500D01*
X354000Y553150D01*
G01X352000D02*
Y554150D01*
G01X308383Y565500D02*
Y568000D01*
X307342D01*
X307008Y567875D01*
X306800Y567708D01*
X306717Y567375D01*
X306800Y567042D01*
X307050Y566833D01*
X307342Y566708D01*
X308383D01*
G01X307342D02*
X306717Y565500D01*
G01X305367Y566000D02*
X305117Y565708D01*
X304783Y565542D01*
X304408Y565500D01*
X304075Y565542D01*
X303742Y565750D01*
X303533Y566000D01*
X303492Y566250D01*
X303575Y566542D01*
X303867Y566750D01*
X304158Y566833D01*
X304533D01*
G01X304158D02*
X303908Y566958D01*
X303700Y567167D01*
X303617Y567417D01*
X303700Y567667D01*
X303908Y567875D01*
X304283Y568000D01*
X304658Y567958D01*
X305033Y567792D01*
G01X301350Y565500D02*
X301058Y565542D01*
X300725Y565667D01*
X300517Y565875D01*
X300433Y566167D01*
X300517Y566458D01*
X300767Y566708D01*
X301142Y566833D01*
X301558D01*
X301808Y566917D01*
X302017Y567125D01*
X302100Y567417D01*
X301975Y567708D01*
X301683Y567917D01*
X301350Y568000D01*
X301017Y567917D01*
X300725Y567708D01*
X300600Y567417D01*
X300683Y567125D01*
X300892Y566917D01*
X301142Y566833D01*
X301558D01*
X301933Y566708D01*
X302183Y566458D01*
X302267Y566167D01*
X302183Y565875D01*
X301975Y565667D01*
X301642Y565542D01*
X301350Y565500D01*
G01X299167Y565875D02*
X298917Y565667D01*
X298625Y565542D01*
X298250Y565500D01*
X297875Y565583D01*
X297583Y565750D01*
X297375Y566042D01*
X297333Y566375D01*
X297417Y566708D01*
X297625Y566917D01*
X297917Y567083D01*
X298208Y567125D01*
X298500Y567083D01*
X298875Y566917D01*
X298750Y568000D01*
X297625D01*
G01X291120Y559123D02*
Y563123D01*
X298520D01*
G01X300000Y548017D02*
X302500D01*
Y549058D01*
X302375Y549392D01*
X302208Y549600D01*
X301875Y549683D01*
X301542Y549600D01*
X301333Y549350D01*
X301208Y549058D01*
Y548017D01*
G01Y549058D02*
X300000Y549683D01*
G01X300500Y551033D02*
X300208Y551283D01*
X300042Y551617D01*
X300000Y551992D01*
X300042Y552325D01*
X300250Y552658D01*
X300500Y552867D01*
X300750Y552908D01*
X301042Y552825D01*
X301250Y552533D01*
X301333Y552242D01*
Y551867D01*
G01Y552242D02*
X301458Y552492D01*
X301667Y552700D01*
X301917Y552783D01*
X302167Y552700D01*
X302375Y552492D01*
X302500Y552117D01*
X302458Y551742D01*
X302292Y551367D01*
G01X300000Y555050D02*
X300042Y555342D01*
X300167Y555675D01*
X300375Y555883D01*
X300667Y555967D01*
X300958Y555883D01*
X301208Y555633D01*
X301333Y555258D01*
Y554842D01*
X301417Y554592D01*
X301625Y554383D01*
X301917Y554300D01*
X302208Y554425D01*
X302417Y554717D01*
X302500Y555050D01*
X302417Y555383D01*
X302208Y555675D01*
X301917Y555800D01*
X301625Y555717D01*
X301417Y555508D01*
X301333Y555258D01*
Y554842D01*
X301208Y554467D01*
X300958Y554217D01*
X300667Y554133D01*
X300375Y554217D01*
X300167Y554425D01*
X300042Y554758D01*
X300000Y555050D01*
G01X302500Y558150D02*
X302417Y557817D01*
X302208Y557567D01*
X301958Y557400D01*
X301625Y557275D01*
X301250Y557233D01*
X300875Y557275D01*
X300542Y557400D01*
X300292Y557567D01*
X300083Y557817D01*
X300000Y558150D01*
X300083Y558483D01*
X300292Y558733D01*
X300542Y558900D01*
X300875Y559025D01*
X301250Y559067D01*
X301625Y559025D01*
X301958Y558900D01*
X302208Y558733D01*
X302417Y558483D01*
X302500Y558150D01*
G01X298680Y550864D02*
X294680D01*
Y558264D01*
G01X335300Y501317D02*
X337800D01*
Y502358D01*
X337675Y502692D01*
X337508Y502900D01*
X337175Y502983D01*
X336842Y502900D01*
X336633Y502650D01*
X336508Y502358D01*
Y501317D01*
G01Y502358D02*
X335300Y502983D01*
G01Y505167D02*
X335842Y505250D01*
X336300Y505375D01*
X336717Y505542D01*
X337175Y505750D01*
X337800Y506083D01*
Y504417D01*
G01X335300Y508350D02*
X337800D01*
X337300Y507850D01*
G01X335300D02*
Y508850D01*
G01Y511450D02*
X335342Y511742D01*
X335467Y512075D01*
X335675Y512283D01*
X335967Y512367D01*
X336258Y512283D01*
X336508Y512033D01*
X336633Y511658D01*
Y511242D01*
X336717Y510992D01*
X336925Y510783D01*
X337217Y510700D01*
X337508Y510825D01*
X337717Y511117D01*
X337800Y511450D01*
X337717Y511783D01*
X337508Y512075D01*
X337217Y512200D01*
X336925Y512117D01*
X336717Y511908D01*
X336633Y511658D01*
Y511242D01*
X336508Y510867D01*
X336258Y510617D01*
X335967Y510533D01*
X335675Y510617D01*
X335467Y510825D01*
X335342Y511158D01*
X335300Y511450D01*
G01X328600Y511300D02*
X332600D01*
Y503900D01*
G01X325695Y551794D02*
Y554294D01*
X324654D01*
X324320Y554169D01*
X324112Y554002D01*
X324029Y553669D01*
X324112Y553336D01*
X324362Y553127D01*
X324654Y553002D01*
X325695D01*
G01X324654D02*
X324029Y551794D01*
G01X321762D02*
Y554294D01*
X322262Y553794D01*
G01Y551794D02*
X321262D01*
G01X319454Y553877D02*
X319204Y554127D01*
X318912Y554252D01*
X318579Y554294D01*
X318162Y554211D01*
X317870Y554002D01*
X317787Y553752D01*
X317829Y553502D01*
X317995Y553294D01*
X318829Y552877D01*
X319204Y552586D01*
X319454Y552169D01*
X319537Y551794D01*
X317787D01*
G01X315562D02*
X315270Y551836D01*
X314937Y551961D01*
X314729Y552169D01*
X314645Y552461D01*
X314729Y552752D01*
X314979Y553002D01*
X315354Y553127D01*
X315770D01*
X316020Y553211D01*
X316229Y553419D01*
X316312Y553711D01*
X316187Y554002D01*
X315895Y554211D01*
X315562Y554294D01*
X315229Y554211D01*
X314937Y554002D01*
X314812Y553711D01*
X314895Y553419D01*
X315104Y553211D01*
X315354Y553127D01*
X315770D01*
X316145Y553002D01*
X316395Y552752D01*
X316479Y552461D01*
X316395Y552169D01*
X316187Y551961D01*
X315854Y551836D01*
X315562Y551794D01*
G01X326125Y560073D02*
Y556073D01*
X318725D01*
G01X341983Y564500D02*
Y567000D01*
X340942D01*
X340608Y566875D01*
X340400Y566708D01*
X340317Y566375D01*
X340400Y566042D01*
X340650Y565833D01*
X340942Y565708D01*
X341983D01*
G01X340942D02*
X340317Y564500D01*
G01X338050D02*
Y567000D01*
X338550Y566500D01*
G01Y564500D02*
X337550D01*
G01X335742Y566583D02*
X335492Y566833D01*
X335200Y566958D01*
X334867Y567000D01*
X334450Y566917D01*
X334158Y566708D01*
X334075Y566458D01*
X334117Y566208D01*
X334283Y566000D01*
X335117Y565583D01*
X335492Y565292D01*
X335742Y564875D01*
X335825Y564500D01*
X334075D01*
G01X331933D02*
X331850Y565042D01*
X331725Y565500D01*
X331558Y565917D01*
X331350Y566375D01*
X331017Y567000D01*
X332683D01*
G01X329985Y568198D02*
Y564198D01*
X322585D01*
G01X355280Y527400D02*
X368680D01*
G01X355280Y537400D02*
Y527400D01*
G01X368680Y537400D02*
X355280D01*
G01X328067Y522500D02*
Y520708D01*
X327900Y520333D01*
X327567Y520083D01*
X327150Y520000D01*
X326733Y520083D01*
X326400Y520333D01*
X326233Y520708D01*
Y522500D01*
G01X324050Y520000D02*
Y522500D01*
X324550Y522000D01*
G01Y520000D02*
X323550D01*
G01X320950Y522500D02*
X321283Y522417D01*
X321533Y522208D01*
X321700Y521958D01*
X321825Y521625D01*
X321867Y521250D01*
X321825Y520875D01*
X321700Y520542D01*
X321533Y520292D01*
X321283Y520083D01*
X320950Y520000D01*
X320617Y520083D01*
X320367Y520292D01*
X320200Y520542D01*
X320075Y520875D01*
X320033Y521250D01*
X320075Y521625D01*
X320200Y521958D01*
X320367Y522208D01*
X320617Y522417D01*
X320950Y522500D01*
G01X318767Y520500D02*
X318517Y520208D01*
X318183Y520042D01*
X317808Y520000D01*
X317475Y520042D01*
X317142Y520250D01*
X316933Y520500D01*
X316892Y520750D01*
X316975Y521042D01*
X317267Y521250D01*
X317558Y521333D01*
X317933D01*
G01X317558D02*
X317308Y521458D01*
X317100Y521667D01*
X317017Y521917D01*
X317100Y522167D01*
X317308Y522375D01*
X317683Y522500D01*
X318058Y522458D01*
X318433Y522292D01*
G01X312900Y507900D02*
X326300D01*
G01X312900Y517900D02*
Y507900D01*
G01X326300Y517900D02*
X312900D01*
G01X326300Y507900D02*
Y517900D01*
G01X332885Y585249D02*
X333135Y585374D01*
X333427Y585457D01*
X333760D01*
X334135Y585332D01*
X334427Y585124D01*
X334635Y584874D01*
X334802Y584457D01*
X334844Y584082D01*
X334760Y583707D01*
X334635Y583457D01*
X334385Y583207D01*
X334094Y583040D01*
X333802Y582957D01*
X333510D01*
X333219Y583040D01*
X332969Y583165D01*
X332760Y583332D01*
G01X330202Y582957D02*
Y585457D01*
X331744Y583665D01*
X329660D01*
G01X327602Y582957D02*
X327310Y582999D01*
X326977Y583124D01*
X326769Y583332D01*
X326685Y583624D01*
X326769Y583915D01*
X327019Y584165D01*
X327394Y584290D01*
X327810D01*
X328060Y584374D01*
X328269Y584582D01*
X328352Y584874D01*
X328227Y585165D01*
X327935Y585374D01*
X327602Y585457D01*
X327269Y585374D01*
X326977Y585165D01*
X326852Y584874D01*
X326935Y584582D01*
X327144Y584374D01*
X327394Y584290D01*
X327810D01*
X328185Y584165D01*
X328435Y583915D01*
X328519Y583624D01*
X328435Y583332D01*
X328227Y583124D01*
X327894Y582999D01*
X327602Y582957D01*
G01X325419Y583332D02*
X325169Y583124D01*
X324877Y582999D01*
X324502Y582957D01*
X324127Y583040D01*
X323835Y583207D01*
X323627Y583499D01*
X323585Y583832D01*
X323669Y584165D01*
X323877Y584374D01*
X324169Y584540D01*
X324460Y584582D01*
X324752Y584540D01*
X325127Y584374D01*
X325002Y585457D01*
X323877D01*
G01X330076Y609049D02*
X330326Y609174D01*
X330618Y609257D01*
X330951D01*
X331326Y609132D01*
X331618Y608924D01*
X331826Y608674D01*
X331993Y608257D01*
X332035Y607882D01*
X331951Y607507D01*
X331826Y607257D01*
X331576Y607007D01*
X331285Y606840D01*
X330993Y606757D01*
X330701D01*
X330410Y606840D01*
X330160Y606965D01*
X329951Y607132D01*
G01X328810Y607257D02*
X328560Y606965D01*
X328226Y606799D01*
X327851Y606757D01*
X327518Y606799D01*
X327185Y607007D01*
X326976Y607257D01*
X326935Y607507D01*
X327018Y607799D01*
X327310Y608007D01*
X327601Y608090D01*
X327976D01*
G01X327601D02*
X327351Y608215D01*
X327143Y608424D01*
X327060Y608674D01*
X327143Y608924D01*
X327351Y609132D01*
X327726Y609257D01*
X328101Y609215D01*
X328476Y609049D01*
G01X325501Y607049D02*
X325210Y606840D01*
X324876Y606757D01*
X324543Y606840D01*
X324251Y607090D01*
X324043Y607465D01*
X323960Y607840D01*
Y608299D01*
X324043Y608674D01*
X324251Y609007D01*
X324501Y609174D01*
X324793Y609257D01*
X325126Y609174D01*
X325376Y609007D01*
X325543Y608757D01*
X325626Y608424D01*
X325543Y608132D01*
X325335Y607840D01*
X325085Y607674D01*
X324793Y607632D01*
X324460Y607715D01*
X324210Y607924D01*
X323960Y608299D01*
G01X351483Y569500D02*
Y572000D01*
X350442D01*
X350108Y571875D01*
X349900Y571708D01*
X349817Y571375D01*
X349900Y571042D01*
X350150Y570833D01*
X350442Y570708D01*
X351483D01*
G01X350442D02*
X349817Y569500D01*
G01X347050D02*
Y572000D01*
X348592Y570208D01*
X346508D01*
G01X345242Y571583D02*
X344992Y571833D01*
X344700Y571958D01*
X344367Y572000D01*
X343950Y571917D01*
X343658Y571708D01*
X343575Y571458D01*
X343617Y571208D01*
X343783Y571000D01*
X344617Y570583D01*
X344992Y570292D01*
X345242Y569875D01*
X345325Y569500D01*
X343575D01*
G01X340850D02*
Y572000D01*
X342392Y570208D01*
X340308D01*
G01X342200Y572900D02*
Y576900D01*
X349600D01*
G01X355000Y592200D02*
X359000D01*
Y584800D01*
G01X348483Y582000D02*
Y584500D01*
X347442D01*
X347108Y584375D01*
X346900Y584208D01*
X346817Y583875D01*
X346900Y583542D01*
X347150Y583333D01*
X347442Y583208D01*
X348483D01*
G01X347442D02*
X346817Y582000D01*
G01X344050D02*
Y584500D01*
X345592Y582708D01*
X343508D01*
G01X342242Y584083D02*
X341992Y584333D01*
X341700Y584458D01*
X341367Y584500D01*
X340950Y584417D01*
X340658Y584208D01*
X340575Y583958D01*
X340617Y583708D01*
X340783Y583500D01*
X341617Y583083D01*
X341992Y582792D01*
X342242Y582375D01*
X342325Y582000D01*
X340575D01*
G01X339058Y582292D02*
X338767Y582083D01*
X338433Y582000D01*
X338100Y582083D01*
X337808Y582333D01*
X337600Y582708D01*
X337517Y583083D01*
Y583542D01*
X337600Y583917D01*
X337808Y584250D01*
X338058Y584417D01*
X338350Y584500D01*
X338683Y584417D01*
X338933Y584250D01*
X339100Y584000D01*
X339183Y583667D01*
X339100Y583375D01*
X338892Y583083D01*
X338642Y582917D01*
X338350Y582875D01*
X338017Y582958D01*
X337767Y583167D01*
X337517Y583542D01*
G01X349600Y581231D02*
Y577231D01*
X342200D01*
G01X333483Y574500D02*
Y577000D01*
X332442D01*
X332108Y576875D01*
X331900Y576708D01*
X331817Y576375D01*
X331900Y576042D01*
X332150Y575833D01*
X332442Y575708D01*
X333483D01*
G01X332442D02*
X331817Y574500D01*
G01X329633D02*
X329550Y575042D01*
X329425Y575500D01*
X329258Y575917D01*
X329050Y576375D01*
X328717Y577000D01*
X330383D01*
G01X327242Y576583D02*
X326992Y576833D01*
X326700Y576958D01*
X326367Y577000D01*
X325950Y576917D01*
X325658Y576708D01*
X325575Y576458D01*
X325617Y576208D01*
X325783Y576000D01*
X326617Y575583D01*
X326992Y575292D01*
X327242Y574875D01*
X327325Y574500D01*
X325575D01*
G01X323350Y577000D02*
X323683Y576917D01*
X323933Y576708D01*
X324100Y576458D01*
X324225Y576125D01*
X324267Y575750D01*
X324225Y575375D01*
X324100Y575042D01*
X323933Y574792D01*
X323683Y574583D01*
X323350Y574500D01*
X323017Y574583D01*
X322767Y574792D01*
X322600Y575042D01*
X322475Y575375D01*
X322433Y575750D01*
X322475Y576125D01*
X322600Y576458D01*
X322767Y576708D01*
X323017Y576917D01*
X323350Y577000D01*
G01X330156Y573267D02*
Y569267D01*
X322756D01*
G01X293153Y568939D02*
Y571439D01*
X292112D01*
X291778Y571314D01*
X291570Y571147D01*
X291487Y570814D01*
X291570Y570481D01*
X291820Y570272D01*
X292112Y570147D01*
X293153D01*
G01X292112D02*
X291487Y568939D01*
G01X290137Y569314D02*
X289887Y569106D01*
X289595Y568981D01*
X289220Y568939D01*
X288845Y569022D01*
X288553Y569189D01*
X288345Y569481D01*
X288303Y569814D01*
X288387Y570147D01*
X288595Y570356D01*
X288887Y570522D01*
X289178Y570564D01*
X289470Y570522D01*
X289845Y570356D01*
X289720Y571439D01*
X288595D01*
G01X287037Y569439D02*
X286787Y569147D01*
X286453Y568981D01*
X286078Y568939D01*
X285745Y568981D01*
X285412Y569189D01*
X285203Y569439D01*
X285162Y569689D01*
X285245Y569981D01*
X285537Y570189D01*
X285828Y570272D01*
X286203D01*
G01X285828D02*
X285578Y570397D01*
X285370Y570606D01*
X285287Y570856D01*
X285370Y571106D01*
X285578Y571314D01*
X285953Y571439D01*
X286328Y571397D01*
X286703Y571231D01*
G01X290286Y574320D02*
X286286D01*
Y581720D01*
G01Y589255D02*
X290286D01*
Y581855D01*
G01X324131Y611045D02*
Y613545D01*
X323090D01*
X322756Y613420D01*
X322548Y613253D01*
X322465Y612920D01*
X322548Y612587D01*
X322798Y612378D01*
X323090Y612253D01*
X324131D01*
G01X323090D02*
X322465Y611045D01*
G01X320198D02*
Y613545D01*
X320698Y613045D01*
G01Y611045D02*
X319698D01*
G01X317098Y613545D02*
X317431Y613462D01*
X317681Y613253D01*
X317848Y613003D01*
X317973Y612670D01*
X318015Y612295D01*
X317973Y611920D01*
X317848Y611587D01*
X317681Y611337D01*
X317431Y611128D01*
X317098Y611045D01*
X316765Y611128D01*
X316515Y611337D01*
X316348Y611587D01*
X316223Y611920D01*
X316181Y612295D01*
X316223Y612670D01*
X316348Y613003D01*
X316515Y613253D01*
X316765Y613462D01*
X317098Y613545D01*
G01X313998D02*
X314331Y613462D01*
X314581Y613253D01*
X314748Y613003D01*
X314873Y612670D01*
X314915Y612295D01*
X314873Y611920D01*
X314748Y611587D01*
X314581Y611337D01*
X314331Y611128D01*
X313998Y611045D01*
X313665Y611128D01*
X313415Y611337D01*
X313248Y611587D01*
X313123Y611920D01*
X313081Y612295D01*
X313123Y612670D01*
X313248Y613003D01*
X313415Y613253D01*
X313665Y613462D01*
X313998Y613545D01*
G01X312622Y604283D02*
Y608283D01*
X320022D01*
G01X308169Y611015D02*
X310669D01*
Y612056D01*
X310544Y612390D01*
X310377Y612598D01*
X310044Y612681D01*
X309711Y612598D01*
X309502Y612348D01*
X309377Y612056D01*
Y611015D01*
G01Y612056D02*
X308169Y612681D01*
G01Y614948D02*
X310669D01*
X310169Y614448D01*
G01X308169D02*
Y615448D01*
G01X310669Y618048D02*
X310586Y617715D01*
X310377Y617465D01*
X310127Y617298D01*
X309794Y617173D01*
X309419Y617131D01*
X309044Y617173D01*
X308711Y617298D01*
X308461Y617465D01*
X308252Y617715D01*
X308169Y618048D01*
X308252Y618381D01*
X308461Y618631D01*
X308711Y618798D01*
X309044Y618923D01*
X309419Y618965D01*
X309794Y618923D01*
X310127Y618798D01*
X310377Y618631D01*
X310586Y618381D01*
X310669Y618048D01*
G01X308169Y621148D02*
X310669D01*
X310169Y620648D01*
G01X308169D02*
Y621648D01*
G01X311765Y598300D02*
X307765D01*
Y605700D01*
G01X350000Y591567D02*
X352500D01*
Y592608D01*
X352375Y592942D01*
X352208Y593150D01*
X351875Y593233D01*
X351542Y593150D01*
X351333Y592900D01*
X351208Y592608D01*
Y591567D01*
G01Y592608D02*
X350000Y593233D01*
G01X350292Y594792D02*
X350083Y595083D01*
X350000Y595417D01*
X350083Y595750D01*
X350333Y596042D01*
X350708Y596250D01*
X351083Y596333D01*
X351542D01*
X351917Y596250D01*
X352250Y596042D01*
X352417Y595792D01*
X352500Y595500D01*
X352417Y595167D01*
X352250Y594917D01*
X352000Y594750D01*
X351667Y594667D01*
X351375Y594750D01*
X351083Y594958D01*
X350917Y595208D01*
X350875Y595500D01*
X350958Y595833D01*
X351167Y596083D01*
X351542Y596333D01*
G01X351042Y597808D02*
X351333Y598100D01*
X351500Y598350D01*
X351583Y598683D01*
X351500Y598975D01*
X351333Y599183D01*
X351083Y599350D01*
X350792Y599392D01*
X350542Y599350D01*
X350292Y599183D01*
X350083Y598933D01*
X350000Y598642D01*
X350083Y598308D01*
X350333Y598017D01*
X350708Y597850D01*
X351125Y597808D01*
X351667Y597892D01*
X351958Y598017D01*
X352250Y598225D01*
X352458Y598517D01*
X352500Y598808D01*
X352417Y599100D01*
X352208Y599308D01*
G01X349500Y589490D02*
X353500D01*
Y582090D01*
G01X340717Y599930D02*
X343217D01*
Y600971D01*
X343092Y601305D01*
X342925Y601513D01*
X342592Y601596D01*
X342259Y601513D01*
X342050Y601263D01*
X341925Y600971D01*
Y599930D01*
G01Y600971D02*
X340717Y601596D01*
G01X341009Y603155D02*
X340800Y603446D01*
X340717Y603780D01*
X340800Y604113D01*
X341050Y604405D01*
X341425Y604613D01*
X341800Y604696D01*
X342259D01*
X342634Y604613D01*
X342967Y604405D01*
X343134Y604155D01*
X343217Y603863D01*
X343134Y603530D01*
X342967Y603280D01*
X342717Y603113D01*
X342384Y603030D01*
X342092Y603113D01*
X341800Y603321D01*
X341634Y603571D01*
X341592Y603863D01*
X341675Y604196D01*
X341884Y604446D01*
X342259Y604696D01*
G01X340717Y606880D02*
X341259Y606963D01*
X341717Y607088D01*
X342134Y607255D01*
X342592Y607463D01*
X343217Y607796D01*
Y606130D01*
G01X346102Y589263D02*
X342102D01*
Y596663D01*
G01X357600Y628500D02*
Y626000D01*
G01X358558Y628500D02*
X356642D01*
G01X355333Y626000D02*
Y628500D01*
X354333D01*
X354000Y628375D01*
X353750Y628083D01*
X353667Y627750D01*
X353750Y627417D01*
X353958Y627167D01*
X354333Y627042D01*
X355333D01*
G01X350900Y626000D02*
Y628500D01*
X352442Y626708D01*
X350358D01*
G01X339355Y601300D02*
Y599508D01*
X339188Y599133D01*
X338855Y598883D01*
X338438Y598800D01*
X338021Y598883D01*
X337688Y599133D01*
X337521Y599508D01*
Y601300D01*
G01X335338Y598800D02*
Y601300D01*
X335838Y600800D01*
G01Y598800D02*
X334838D01*
G01X333155Y599175D02*
X332905Y598967D01*
X332613Y598842D01*
X332238Y598800D01*
X331863Y598883D01*
X331571Y599050D01*
X331363Y599342D01*
X331321Y599675D01*
X331405Y600008D01*
X331613Y600217D01*
X331905Y600383D01*
X332196Y600425D01*
X332488Y600383D01*
X332863Y600217D01*
X332738Y601300D01*
X331613D01*
G01X327552Y587153D02*
X340952D01*
G01X327552Y597153D02*
Y587153D01*
G01X340952Y597153D02*
X327552D01*
G01X340952Y587153D02*
Y597153D01*
G01X304984Y608202D02*
Y606410D01*
X304817Y606035D01*
X304484Y605785D01*
X304067Y605702D01*
X303650Y605785D01*
X303317Y606035D01*
X303150Y606410D01*
Y608202D01*
G01X300967Y605702D02*
Y608202D01*
X301467Y607702D01*
G01Y605702D02*
X300467D01*
G01X298659Y606744D02*
X298367Y607035D01*
X298117Y607202D01*
X297784Y607285D01*
X297492Y607202D01*
X297284Y607035D01*
X297117Y606785D01*
X297075Y606494D01*
X297117Y606244D01*
X297284Y605994D01*
X297534Y605785D01*
X297825Y605702D01*
X298159Y605785D01*
X298450Y606035D01*
X298617Y606410D01*
X298659Y606827D01*
X298575Y607369D01*
X298450Y607660D01*
X298242Y607952D01*
X297950Y608160D01*
X297659Y608202D01*
X297367Y608119D01*
X297159Y607910D01*
G01X293300Y593200D02*
X306700D01*
G01X293300Y603200D02*
Y593200D01*
G01X306700Y603200D02*
X293300D01*
G01X306700Y593200D02*
Y603200D01*
G01X344953Y634717D02*
X345078Y634467D01*
X345161Y634175D01*
Y633842D01*
X345036Y633467D01*
X344828Y633175D01*
X344578Y632967D01*
X344161Y632800D01*
X343786Y632758D01*
X343411Y632842D01*
X343161Y632967D01*
X342911Y633217D01*
X342744Y633508D01*
X342661Y633800D01*
Y634092D01*
X342744Y634383D01*
X342869Y634633D01*
X343036Y634842D01*
G01X342661Y636900D02*
X345161D01*
X344661Y636400D01*
G01X342661D02*
Y637400D01*
G01X343703Y639208D02*
X343994Y639500D01*
X344161Y639750D01*
X344244Y640083D01*
X344161Y640375D01*
X343994Y640583D01*
X343744Y640750D01*
X343453Y640792D01*
X343203Y640750D01*
X342953Y640583D01*
X342744Y640333D01*
X342661Y640042D01*
X342744Y639708D01*
X342994Y639417D01*
X343369Y639250D01*
X343786Y639208D01*
X344328Y639292D01*
X344619Y639417D01*
X344911Y639625D01*
X345119Y639917D01*
X345161Y640208D01*
X345078Y640500D01*
X344869Y640708D01*
G01X340153Y634717D02*
X340278Y634467D01*
X340361Y634175D01*
Y633842D01*
X340236Y633467D01*
X340028Y633175D01*
X339778Y632967D01*
X339361Y632800D01*
X338986Y632758D01*
X338611Y632842D01*
X338361Y632967D01*
X338111Y633217D01*
X337944Y633508D01*
X337861Y633800D01*
Y634092D01*
X337944Y634383D01*
X338069Y634633D01*
X338236Y634842D01*
G01X337861Y636900D02*
X340361D01*
X339861Y636400D01*
G01X337861D02*
Y637400D01*
G01X338236Y639083D02*
X338028Y639333D01*
X337903Y639625D01*
X337861Y640000D01*
X337944Y640375D01*
X338111Y640667D01*
X338403Y640875D01*
X338736Y640917D01*
X339069Y640833D01*
X339278Y640625D01*
X339444Y640333D01*
X339486Y640042D01*
X339444Y639750D01*
X339278Y639375D01*
X340361Y639500D01*
Y640625D01*
G01X318017Y589500D02*
Y587708D01*
X317850Y587333D01*
X317517Y587083D01*
X317100Y587000D01*
X316683Y587083D01*
X316350Y587333D01*
X316183Y587708D01*
Y589500D01*
G01X313500Y587000D02*
Y589500D01*
X315042Y587708D01*
X312958D01*
G01X311817Y587375D02*
X311567Y587167D01*
X311275Y587042D01*
X310900Y587000D01*
X310525Y587083D01*
X310233Y587250D01*
X310025Y587542D01*
X309983Y587875D01*
X310067Y588208D01*
X310275Y588417D01*
X310567Y588583D01*
X310858Y588625D01*
X311150Y588583D01*
X311525Y588417D01*
X311400Y589500D01*
X310275D01*
G01X301392Y583389D02*
Y573189D01*
G01X305992Y583389D02*
X301392D01*
G01X305992Y572489D02*
Y583389D01*
G01Y572489D02*
X294692D01*
G01X303692Y573689D02*
X304892Y572489D01*
G01X303692Y573689D02*
X302492Y572489D01*
G01X355183Y618792D02*
X355433Y618917D01*
X355725Y619000D01*
X356058D01*
X356433Y618875D01*
X356725Y618667D01*
X356933Y618417D01*
X357100Y618000D01*
X357142Y617625D01*
X357058Y617250D01*
X356933Y617000D01*
X356683Y616750D01*
X356392Y616583D01*
X356100Y616500D01*
X355808D01*
X355517Y616583D01*
X355267Y616708D01*
X355058Y616875D01*
G01X353000Y616500D02*
Y619000D01*
X353500Y618500D01*
G01Y616500D02*
X352500D01*
G01X350692Y618583D02*
X350442Y618833D01*
X350150Y618958D01*
X349817Y619000D01*
X349400Y618917D01*
X349108Y618708D01*
X349025Y618458D01*
X349067Y618208D01*
X349233Y618000D01*
X350067Y617583D01*
X350442Y617292D01*
X350692Y616875D01*
X350775Y616500D01*
X349025D01*
G01X358664Y597813D02*
X358789Y597563D01*
X358872Y597271D01*
Y596938D01*
X358747Y596563D01*
X358539Y596271D01*
X358289Y596063D01*
X357872Y595896D01*
X357497Y595854D01*
X357122Y595938D01*
X356872Y596063D01*
X356622Y596313D01*
X356455Y596604D01*
X356372Y596896D01*
Y597188D01*
X356455Y597479D01*
X356580Y597729D01*
X356747Y597938D01*
G01X356372Y599996D02*
X358872D01*
X358372Y599496D01*
G01X356372D02*
Y600496D01*
G01X358872Y603096D02*
X358789Y602763D01*
X358580Y602513D01*
X358330Y602346D01*
X357997Y602221D01*
X357622Y602179D01*
X357247Y602221D01*
X356914Y602346D01*
X356664Y602513D01*
X356455Y602763D01*
X356372Y603096D01*
X356455Y603429D01*
X356664Y603679D01*
X356914Y603846D01*
X357247Y603971D01*
X357622Y604013D01*
X357997Y603971D01*
X358330Y603846D01*
X358580Y603679D01*
X358789Y603429D01*
X358872Y603096D01*
G01X362835Y663505D02*
Y659505D01*
X355435D01*
G01X355533Y671696D02*
Y675696D01*
X362933D01*
G01X363169Y684564D02*
Y687064D01*
X362128D01*
X361794Y686939D01*
X361586Y686772D01*
X361503Y686439D01*
X361586Y686106D01*
X361836Y685897D01*
X362128Y685772D01*
X363169D01*
G01X362128D02*
X361503Y684564D01*
G01X358736D02*
Y687064D01*
X360278Y685272D01*
X358194D01*
G01X356136Y684564D02*
Y687064D01*
X356636Y686564D01*
G01Y684564D02*
X355636D01*
G01X353119D02*
X353036Y685106D01*
X352911Y685564D01*
X352744Y685981D01*
X352536Y686439D01*
X352203Y687064D01*
X353869D01*
G01X359655Y675745D02*
X355655D01*
Y683145D01*
G01X295808Y658031D02*
Y660531D01*
X294767D01*
X294433Y660406D01*
X294225Y660239D01*
X294142Y659906D01*
X294225Y659573D01*
X294475Y659364D01*
X294767Y659239D01*
X295808D01*
G01X294767D02*
X294142Y658031D01*
G01X292792Y658531D02*
X292542Y658239D01*
X292208Y658073D01*
X291833Y658031D01*
X291500Y658073D01*
X291167Y658281D01*
X290958Y658531D01*
X290917Y658781D01*
X291000Y659073D01*
X291292Y659281D01*
X291583Y659364D01*
X291958D01*
G01X291583D02*
X291333Y659489D01*
X291125Y659698D01*
X291042Y659948D01*
X291125Y660198D01*
X291333Y660406D01*
X291708Y660531D01*
X292083Y660489D01*
X292458Y660323D01*
G01X289692Y658531D02*
X289442Y658239D01*
X289108Y658073D01*
X288733Y658031D01*
X288400Y658073D01*
X288067Y658281D01*
X287858Y658531D01*
X287817Y658781D01*
X287900Y659073D01*
X288192Y659281D01*
X288483Y659364D01*
X288858D01*
G01X288483D02*
X288233Y659489D01*
X288025Y659698D01*
X287942Y659948D01*
X288025Y660198D01*
X288233Y660406D01*
X288608Y660531D01*
X288983Y660489D01*
X289358Y660323D01*
G01X285675Y660531D02*
X286008Y660448D01*
X286258Y660239D01*
X286425Y659989D01*
X286550Y659656D01*
X286592Y659281D01*
X286550Y658906D01*
X286425Y658573D01*
X286258Y658323D01*
X286008Y658114D01*
X285675Y658031D01*
X285342Y658114D01*
X285092Y658323D01*
X284925Y658573D01*
X284800Y658906D01*
X284758Y659281D01*
X284800Y659656D01*
X284925Y659989D01*
X285092Y660239D01*
X285342Y660448D01*
X285675Y660531D01*
G01X302400Y659300D02*
Y663300D01*
X309800D01*
G01X355400Y663580D02*
Y667580D01*
X362800D01*
G01X313315Y685199D02*
X315815D01*
Y686240D01*
X315690Y686574D01*
X315523Y686782D01*
X315190Y686865D01*
X314857Y686782D01*
X314648Y686532D01*
X314523Y686240D01*
Y685199D01*
G01Y686240D02*
X313315Y686865D01*
G01X313815Y688215D02*
X313523Y688465D01*
X313357Y688799D01*
X313315Y689174D01*
X313357Y689507D01*
X313565Y689840D01*
X313815Y690049D01*
X314065Y690090D01*
X314357Y690007D01*
X314565Y689715D01*
X314648Y689424D01*
Y689049D01*
G01Y689424D02*
X314773Y689674D01*
X314982Y689882D01*
X315232Y689965D01*
X315482Y689882D01*
X315690Y689674D01*
X315815Y689299D01*
X315773Y688924D01*
X315607Y688549D01*
G01X315398Y691440D02*
X315648Y691690D01*
X315773Y691982D01*
X315815Y692315D01*
X315732Y692732D01*
X315523Y693024D01*
X315273Y693107D01*
X315023Y693065D01*
X314815Y692899D01*
X314398Y692065D01*
X314107Y691690D01*
X313690Y691440D01*
X313315Y691357D01*
Y693107D01*
G01Y695249D02*
X313857Y695332D01*
X314315Y695457D01*
X314732Y695624D01*
X315190Y695832D01*
X315815Y696165D01*
Y694499D01*
G01X312800Y683400D02*
X316800D01*
Y676000D01*
G01X309451Y685833D02*
Y688333D01*
X308410D01*
X308076Y688208D01*
X307868Y688041D01*
X307785Y687708D01*
X307868Y687375D01*
X308118Y687166D01*
X308410Y687041D01*
X309451D01*
G01X308410D02*
X307785Y685833D01*
G01X306435Y686333D02*
X306185Y686041D01*
X305851Y685875D01*
X305476Y685833D01*
X305143Y685875D01*
X304810Y686083D01*
X304601Y686333D01*
X304560Y686583D01*
X304643Y686875D01*
X304935Y687083D01*
X305226Y687166D01*
X305601D01*
G01X305226D02*
X304976Y687291D01*
X304768Y687500D01*
X304685Y687750D01*
X304768Y688000D01*
X304976Y688208D01*
X305351Y688333D01*
X305726Y688291D01*
X306101Y688125D01*
G01X302418Y688333D02*
X302751Y688250D01*
X303001Y688041D01*
X303168Y687791D01*
X303293Y687458D01*
X303335Y687083D01*
X303293Y686708D01*
X303168Y686375D01*
X303001Y686125D01*
X302751Y685916D01*
X302418Y685833D01*
X302085Y685916D01*
X301835Y686125D01*
X301668Y686375D01*
X301543Y686708D01*
X301501Y687083D01*
X301543Y687458D01*
X301668Y687791D01*
X301835Y688041D01*
X302085Y688250D01*
X302418Y688333D01*
G01X299318Y685833D02*
Y688333D01*
X299818Y687833D01*
G01Y685833D02*
X298818D01*
G01X311217Y684959D02*
Y680959D01*
X303817D01*
G01X298492Y661273D02*
X300992D01*
Y662314D01*
X300867Y662648D01*
X300700Y662856D01*
X300367Y662939D01*
X300034Y662856D01*
X299825Y662606D01*
X299700Y662314D01*
Y661273D01*
G01Y662314D02*
X298492Y662939D01*
G01Y665706D02*
X300992D01*
X299200Y664164D01*
Y666248D01*
G01X298867Y667389D02*
X298659Y667639D01*
X298534Y667931D01*
X298492Y668306D01*
X298575Y668681D01*
X298742Y668973D01*
X299034Y669181D01*
X299367Y669223D01*
X299700Y669139D01*
X299909Y668931D01*
X300075Y668639D01*
X300117Y668348D01*
X300075Y668056D01*
X299909Y667681D01*
X300992Y667806D01*
Y668931D01*
G01X300575Y670614D02*
X300825Y670864D01*
X300950Y671156D01*
X300992Y671489D01*
X300909Y671906D01*
X300700Y672198D01*
X300450Y672281D01*
X300200Y672239D01*
X299992Y672073D01*
X299575Y671239D01*
X299284Y670864D01*
X298867Y670614D01*
X298492Y670531D01*
Y672281D01*
G01X314000Y661300D02*
X310000D01*
Y668700D01*
G01X296898Y662165D02*
Y664665D01*
X295857D01*
X295523Y664540D01*
X295315Y664373D01*
X295232Y664040D01*
X295315Y663707D01*
X295565Y663498D01*
X295857Y663373D01*
X296898D01*
G01X295857D02*
X295232Y662165D01*
G01X293882Y662665D02*
X293632Y662373D01*
X293298Y662207D01*
X292923Y662165D01*
X292590Y662207D01*
X292257Y662415D01*
X292048Y662665D01*
X292007Y662915D01*
X292090Y663207D01*
X292382Y663415D01*
X292673Y663498D01*
X293048D01*
G01X292673D02*
X292423Y663623D01*
X292215Y663832D01*
X292132Y664082D01*
X292215Y664332D01*
X292423Y664540D01*
X292798Y664665D01*
X293173Y664623D01*
X293548Y664457D01*
G01X289865Y664665D02*
X290198Y664582D01*
X290448Y664373D01*
X290615Y664123D01*
X290740Y663790D01*
X290782Y663415D01*
X290740Y663040D01*
X290615Y662707D01*
X290448Y662457D01*
X290198Y662248D01*
X289865Y662165D01*
X289532Y662248D01*
X289282Y662457D01*
X289115Y662707D01*
X288990Y663040D01*
X288948Y663415D01*
X288990Y663790D01*
X289115Y664123D01*
X289282Y664373D01*
X289532Y664582D01*
X289865Y664665D01*
G01X287557Y664248D02*
X287307Y664498D01*
X287015Y664623D01*
X286682Y664665D01*
X286265Y664582D01*
X285973Y664373D01*
X285890Y664123D01*
X285932Y663873D01*
X286098Y663665D01*
X286932Y663248D01*
X287307Y662957D01*
X287557Y662540D01*
X287640Y662165D01*
X285890D01*
G01X309849Y663500D02*
X305849D01*
Y670900D01*
G01X340517Y657500D02*
Y655708D01*
X340350Y655333D01*
X340017Y655083D01*
X339600Y655000D01*
X339183Y655083D01*
X338850Y655333D01*
X338683Y655708D01*
Y657500D01*
G01X337417Y655500D02*
X337167Y655208D01*
X336833Y655042D01*
X336458Y655000D01*
X336125Y655042D01*
X335792Y655250D01*
X335583Y655500D01*
X335542Y655750D01*
X335625Y656042D01*
X335917Y656250D01*
X336208Y656333D01*
X336583D01*
G01X336208D02*
X335958Y656458D01*
X335750Y656667D01*
X335667Y656917D01*
X335750Y657167D01*
X335958Y657375D01*
X336333Y657500D01*
X336708Y657458D01*
X337083Y657292D01*
G01X334192Y657083D02*
X333942Y657333D01*
X333650Y657458D01*
X333317Y657500D01*
X332900Y657417D01*
X332608Y657208D01*
X332525Y656958D01*
X332567Y656708D01*
X332733Y656500D01*
X333567Y656083D01*
X333942Y655792D01*
X334192Y655375D01*
X334275Y655000D01*
X332525D01*
G01X366640Y30195D02*
Y32695D01*
X365599D01*
X365265Y32570D01*
X365057Y32403D01*
X364974Y32070D01*
X365057Y31737D01*
X365307Y31528D01*
X365599Y31403D01*
X366640D01*
G01X365599D02*
X364974Y30195D01*
G01X363624Y30695D02*
X363374Y30403D01*
X363040Y30237D01*
X362665Y30195D01*
X362332Y30237D01*
X361999Y30445D01*
X361790Y30695D01*
X361749Y30945D01*
X361832Y31237D01*
X362124Y31445D01*
X362415Y31528D01*
X362790D01*
G01X362415D02*
X362165Y31653D01*
X361957Y31862D01*
X361874Y32112D01*
X361957Y32362D01*
X362165Y32570D01*
X362540Y32695D01*
X362915Y32653D01*
X363290Y32487D01*
G01X359690Y30195D02*
X359607Y30737D01*
X359482Y31195D01*
X359315Y31612D01*
X359107Y32070D01*
X358774Y32695D01*
X360440D01*
G01X371800Y29000D02*
Y33000D01*
X379200D01*
G01X378300Y20500D02*
X383800D01*
Y28500D01*
X378200D01*
G01X366200Y20500D02*
X371700D01*
G01X366200D02*
Y28500D01*
X371700D01*
G01X379288Y541129D02*
X379538Y541254D01*
X379830Y541337D01*
X380163D01*
X380538Y541212D01*
X380830Y541004D01*
X381038Y540754D01*
X381205Y540337D01*
X381247Y539962D01*
X381163Y539587D01*
X381038Y539337D01*
X380788Y539087D01*
X380497Y538920D01*
X380205Y538837D01*
X379913D01*
X379622Y538920D01*
X379372Y539045D01*
X379163Y539212D01*
G01X378022D02*
X377772Y539004D01*
X377480Y538879D01*
X377105Y538837D01*
X376730Y538920D01*
X376438Y539087D01*
X376230Y539379D01*
X376188Y539712D01*
X376272Y540045D01*
X376480Y540254D01*
X376772Y540420D01*
X377063Y540462D01*
X377355Y540420D01*
X377730Y540254D01*
X377605Y541337D01*
X376480D01*
G01X374005D02*
X374338Y541254D01*
X374588Y541045D01*
X374755Y540795D01*
X374880Y540462D01*
X374922Y540087D01*
X374880Y539712D01*
X374755Y539379D01*
X374588Y539129D01*
X374338Y538920D01*
X374005Y538837D01*
X373672Y538920D01*
X373422Y539129D01*
X373255Y539379D01*
X373130Y539712D01*
X373088Y540087D01*
X373130Y540462D01*
X373255Y540795D01*
X373422Y541045D01*
X373672Y541254D01*
X374005Y541337D01*
G01X370405Y538837D02*
Y541337D01*
X371947Y539545D01*
X369863D01*
G01X383733Y511292D02*
X383983Y511417D01*
X384275Y511500D01*
X384608D01*
X384983Y511375D01*
X385275Y511167D01*
X385483Y510917D01*
X385650Y510500D01*
X385692Y510125D01*
X385608Y509750D01*
X385483Y509500D01*
X385233Y509250D01*
X384942Y509083D01*
X384650Y509000D01*
X384358D01*
X384067Y509083D01*
X383817Y509208D01*
X383608Y509375D01*
G01X381550Y509000D02*
Y511500D01*
X382050Y511000D01*
G01Y509000D02*
X381050D01*
G01X379242Y511083D02*
X378992Y511333D01*
X378700Y511458D01*
X378367Y511500D01*
X377950Y511417D01*
X377658Y511208D01*
X377575Y510958D01*
X377617Y510708D01*
X377783Y510500D01*
X378617Y510083D01*
X378992Y509792D01*
X379242Y509375D01*
X379325Y509000D01*
X377575D01*
G01X376142Y510042D02*
X375850Y510333D01*
X375600Y510500D01*
X375267Y510583D01*
X374975Y510500D01*
X374767Y510333D01*
X374600Y510083D01*
X374558Y509792D01*
X374600Y509542D01*
X374767Y509292D01*
X375017Y509083D01*
X375308Y509000D01*
X375642Y509083D01*
X375933Y509333D01*
X376100Y509708D01*
X376142Y510125D01*
X376058Y510667D01*
X375933Y510958D01*
X375725Y511250D01*
X375433Y511458D01*
X375142Y511500D01*
X374850Y511417D01*
X374642Y511208D01*
G01X381733Y552792D02*
X381983Y552917D01*
X382275Y553000D01*
X382608D01*
X382983Y552875D01*
X383275Y552667D01*
X383483Y552417D01*
X383650Y552000D01*
X383692Y551625D01*
X383608Y551250D01*
X383483Y551000D01*
X383233Y550750D01*
X382942Y550583D01*
X382650Y550500D01*
X382358D01*
X382067Y550583D01*
X381817Y550708D01*
X381608Y550875D01*
G01X379550Y550500D02*
Y553000D01*
X380050Y552500D01*
G01Y550500D02*
X379050D01*
G01X377367Y551000D02*
X377117Y550708D01*
X376783Y550542D01*
X376408Y550500D01*
X376075Y550542D01*
X375742Y550750D01*
X375533Y551000D01*
X375492Y551250D01*
X375575Y551542D01*
X375867Y551750D01*
X376158Y551833D01*
X376533D01*
G01X376158D02*
X375908Y551958D01*
X375700Y552167D01*
X375617Y552417D01*
X375700Y552667D01*
X375908Y552875D01*
X376283Y553000D01*
X376658Y552958D01*
X377033Y552792D01*
G01X373433Y550500D02*
X373350Y551042D01*
X373225Y551500D01*
X373058Y551917D01*
X372850Y552375D01*
X372517Y553000D01*
X374183D01*
G01X381983Y543500D02*
Y546000D01*
X380942D01*
X380608Y545875D01*
X380400Y545708D01*
X380317Y545375D01*
X380400Y545042D01*
X380650Y544833D01*
X380942Y544708D01*
X381983D01*
G01X380942D02*
X380317Y543500D01*
G01X378842Y545583D02*
X378592Y545833D01*
X378300Y545958D01*
X377967Y546000D01*
X377550Y545917D01*
X377258Y545708D01*
X377175Y545458D01*
X377217Y545208D01*
X377383Y545000D01*
X378217Y544583D01*
X378592Y544292D01*
X378842Y543875D01*
X378925Y543500D01*
X377175D01*
G01X375033D02*
X374950Y544042D01*
X374825Y544500D01*
X374658Y544917D01*
X374450Y545375D01*
X374117Y546000D01*
X375783D01*
G01X372767Y543875D02*
X372517Y543667D01*
X372225Y543542D01*
X371850Y543500D01*
X371475Y543583D01*
X371183Y543750D01*
X370975Y544042D01*
X370933Y544375D01*
X371017Y544708D01*
X371225Y544917D01*
X371517Y545083D01*
X371808Y545125D01*
X372100Y545083D01*
X372475Y544917D01*
X372350Y546000D01*
X371225D01*
G01X367680Y546200D02*
Y542200D01*
X360280D01*
G01X375500Y554517D02*
X378000D01*
Y555558D01*
X377875Y555892D01*
X377708Y556100D01*
X377375Y556183D01*
X377042Y556100D01*
X376833Y555850D01*
X376708Y555558D01*
Y554517D01*
G01Y555558D02*
X375500Y556183D01*
G01Y558367D02*
X376042Y558450D01*
X376500Y558575D01*
X376917Y558742D01*
X377375Y558950D01*
X378000Y559283D01*
Y557617D01*
G01X377583Y560758D02*
X377833Y561008D01*
X377958Y561300D01*
X378000Y561633D01*
X377917Y562050D01*
X377708Y562342D01*
X377458Y562425D01*
X377208Y562383D01*
X377000Y562217D01*
X376583Y561383D01*
X376292Y561008D01*
X375875Y560758D01*
X375500Y560675D01*
Y562425D01*
G01X377583Y563858D02*
X377833Y564108D01*
X377958Y564400D01*
X378000Y564733D01*
X377917Y565150D01*
X377708Y565442D01*
X377458Y565525D01*
X377208Y565483D01*
X377000Y565317D01*
X376583Y564483D01*
X376292Y564108D01*
X375875Y563858D01*
X375500Y563775D01*
Y565525D01*
G01X360120Y542204D02*
X356120D01*
Y549604D01*
G01X377437Y525825D02*
X375645D01*
X375270Y525992D01*
X375020Y526325D01*
X374937Y526742D01*
X375020Y527159D01*
X375270Y527492D01*
X375645Y527659D01*
X377437D01*
G01X374937Y529842D02*
X377437D01*
X376937Y529342D01*
G01X374937D02*
Y530342D01*
G01X377437Y532942D02*
X377354Y532609D01*
X377145Y532359D01*
X376895Y532192D01*
X376562Y532067D01*
X376187Y532025D01*
X375812Y532067D01*
X375479Y532192D01*
X375229Y532359D01*
X375020Y532609D01*
X374937Y532942D01*
X375020Y533275D01*
X375229Y533525D01*
X375479Y533692D01*
X375812Y533817D01*
X376187Y533859D01*
X376562Y533817D01*
X376895Y533692D01*
X377145Y533525D01*
X377354Y533275D01*
X377437Y532942D01*
G01X374937Y536042D02*
X377437D01*
X376937Y535542D01*
G01X374937D02*
Y536542D01*
G01X368680Y527400D02*
Y537400D01*
G01X385529Y523074D02*
Y521282D01*
X385362Y520907D01*
X385029Y520657D01*
X384612Y520574D01*
X384195Y520657D01*
X383862Y520907D01*
X383695Y521282D01*
Y523074D01*
G01X381512Y520574D02*
Y523074D01*
X382012Y522574D01*
G01Y520574D02*
X381012D01*
G01X378412Y523074D02*
X378745Y522991D01*
X378995Y522782D01*
X379162Y522532D01*
X379287Y522199D01*
X379329Y521824D01*
X379287Y521449D01*
X379162Y521116D01*
X378995Y520866D01*
X378745Y520657D01*
X378412Y520574D01*
X378079Y520657D01*
X377829Y520866D01*
X377662Y521116D01*
X377537Y521449D01*
X377495Y521824D01*
X377537Y522199D01*
X377662Y522532D01*
X377829Y522782D01*
X378079Y522991D01*
X378412Y523074D01*
G01X375312D02*
X375645Y522991D01*
X375895Y522782D01*
X376062Y522532D01*
X376187Y522199D01*
X376229Y521824D01*
X376187Y521449D01*
X376062Y521116D01*
X375895Y520866D01*
X375645Y520657D01*
X375312Y520574D01*
X374979Y520657D01*
X374729Y520866D01*
X374562Y521116D01*
X374437Y521449D01*
X374395Y521824D01*
X374437Y522199D01*
X374562Y522532D01*
X374729Y522782D01*
X374979Y522991D01*
X375312Y523074D01*
G01X358300Y515100D02*
X371700D01*
G01X358300Y525100D02*
Y515100D01*
G01X371700Y525100D02*
X358300D01*
G01X371700Y515100D02*
Y525100D01*
G01X379500Y558400D02*
X379542Y558067D01*
X379708Y557775D01*
X379958Y557525D01*
X380250Y557358D01*
X380583Y557275D01*
X380917D01*
X381250Y557358D01*
X381542Y557525D01*
X381792Y557775D01*
X381958Y558067D01*
X382000Y558400D01*
X381958Y558733D01*
X381792Y559025D01*
X381542Y559275D01*
X381250Y559442D01*
X380917Y559525D01*
X380583D01*
X380250Y559442D01*
X379958Y559275D01*
X379708Y559025D01*
X379542Y558733D01*
X379500Y558400D01*
G01X380167Y558733D02*
X379500Y559233D01*
G01X381583Y560708D02*
X381833Y560958D01*
X381958Y561250D01*
X382000Y561583D01*
X381917Y562000D01*
X381708Y562292D01*
X381458Y562375D01*
X381208Y562333D01*
X381000Y562167D01*
X380583Y561333D01*
X380292Y560958D01*
X379875Y560708D01*
X379500Y560625D01*
Y562375D01*
G01X380542Y563808D02*
X380833Y564100D01*
X381000Y564350D01*
X381083Y564683D01*
X381000Y564975D01*
X380833Y565183D01*
X380583Y565350D01*
X380292Y565392D01*
X380042Y565350D01*
X379792Y565183D01*
X379583Y564933D01*
X379500Y564642D01*
X379583Y564308D01*
X379833Y564017D01*
X380208Y563850D01*
X380625Y563808D01*
X381167Y563892D01*
X381458Y564017D01*
X381750Y564225D01*
X381958Y564517D01*
X382000Y564808D01*
X381917Y565100D01*
X381708Y565308D01*
G01X374200Y557000D02*
X360200D01*
G01X374200Y570000D02*
Y557000D01*
G01X360200D02*
Y570000D01*
G01X374792Y586317D02*
X374917Y586067D01*
X375000Y585775D01*
Y585442D01*
X374875Y585067D01*
X374667Y584775D01*
X374417Y584567D01*
X374000Y584400D01*
X373625Y584358D01*
X373250Y584442D01*
X373000Y584567D01*
X372750Y584817D01*
X372583Y585108D01*
X372500Y585400D01*
Y585692D01*
X372583Y585983D01*
X372708Y586233D01*
X372875Y586442D01*
G01X372500Y588500D02*
X375000D01*
X374500Y588000D01*
G01X372500D02*
Y589000D01*
G01Y592100D02*
X375000D01*
X373208Y590558D01*
Y592642D01*
G01X368500Y584567D02*
X371000D01*
Y585608D01*
X370875Y585942D01*
X370708Y586150D01*
X370375Y586233D01*
X370042Y586150D01*
X369833Y585900D01*
X369708Y585608D01*
Y584567D01*
G01Y585608D02*
X368500Y586233D01*
G01Y589000D02*
X371000D01*
X369208Y587458D01*
Y589542D01*
G01X371000Y591600D02*
X370917Y591267D01*
X370708Y591017D01*
X370458Y590850D01*
X370125Y590725D01*
X369750Y590683D01*
X369375Y590725D01*
X369042Y590850D01*
X368792Y591017D01*
X368583Y591267D01*
X368500Y591600D01*
X368583Y591933D01*
X368792Y592183D01*
X369042Y592350D01*
X369375Y592475D01*
X369750Y592517D01*
X370125Y592475D01*
X370458Y592350D01*
X370708Y592183D01*
X370917Y591933D01*
X371000Y591600D01*
G01X395133Y615967D02*
Y618467D01*
X394092D01*
X393758Y618342D01*
X393550Y618175D01*
X393467Y617842D01*
X393550Y617509D01*
X393800Y617300D01*
X394092Y617175D01*
X395133D01*
G01X394092D02*
X393467Y615967D01*
G01X391992Y618050D02*
X391742Y618300D01*
X391450Y618425D01*
X391117Y618467D01*
X390700Y618384D01*
X390408Y618175D01*
X390325Y617925D01*
X390367Y617675D01*
X390533Y617467D01*
X391367Y617050D01*
X391742Y616759D01*
X391992Y616342D01*
X392075Y615967D01*
X390325D01*
G01X388892Y618050D02*
X388642Y618300D01*
X388350Y618425D01*
X388017Y618467D01*
X387600Y618384D01*
X387308Y618175D01*
X387225Y617925D01*
X387267Y617675D01*
X387433Y617467D01*
X388267Y617050D01*
X388642Y616759D01*
X388892Y616342D01*
X388975Y615967D01*
X387225D01*
G01X381315Y619425D02*
Y615425D01*
X373915D01*
G01X372114Y631094D02*
X374614D01*
Y632135D01*
X374489Y632469D01*
X374322Y632677D01*
X373989Y632760D01*
X373656Y632677D01*
X373447Y632427D01*
X373322Y632135D01*
Y631094D01*
G01Y632135D02*
X372114Y632760D01*
G01X374197Y634235D02*
X374447Y634485D01*
X374572Y634777D01*
X374614Y635110D01*
X374531Y635527D01*
X374322Y635819D01*
X374072Y635902D01*
X373822Y635860D01*
X373614Y635694D01*
X373197Y634860D01*
X372906Y634485D01*
X372489Y634235D01*
X372114Y634152D01*
Y635902D01*
G01Y638127D02*
X374614D01*
X374114Y637627D01*
G01X372114D02*
Y638627D01*
G01X371400Y628000D02*
X375400D01*
Y620600D01*
G01X382867Y570717D02*
X385367D01*
Y571758D01*
X385242Y572092D01*
X385075Y572300D01*
X384742Y572383D01*
X384409Y572300D01*
X384200Y572050D01*
X384075Y571758D01*
Y570717D01*
G01Y571758D02*
X382867Y572383D01*
G01Y575150D02*
X385367D01*
X383575Y573608D01*
Y575692D01*
G01X383367Y576833D02*
X383075Y577083D01*
X382909Y577417D01*
X382867Y577792D01*
X382909Y578125D01*
X383117Y578458D01*
X383367Y578667D01*
X383617Y578708D01*
X383909Y578625D01*
X384117Y578333D01*
X384200Y578042D01*
Y577667D01*
G01Y578042D02*
X384325Y578292D01*
X384534Y578500D01*
X384784Y578583D01*
X385034Y578500D01*
X385242Y578292D01*
X385367Y577917D01*
X385325Y577542D01*
X385159Y577167D01*
G01X385367Y580850D02*
X385284Y580517D01*
X385075Y580267D01*
X384825Y580100D01*
X384492Y579975D01*
X384117Y579933D01*
X383742Y579975D01*
X383409Y580100D01*
X383159Y580267D01*
X382950Y580517D01*
X382867Y580850D01*
X382950Y581183D01*
X383159Y581433D01*
X383409Y581600D01*
X383742Y581725D01*
X384117Y581767D01*
X384492Y581725D01*
X384825Y581600D01*
X385075Y581433D01*
X385284Y581183D01*
X385367Y580850D01*
G01X371800Y572600D02*
X367800D01*
Y580000D01*
G01X378867Y570717D02*
X381367D01*
Y571758D01*
X381242Y572092D01*
X381075Y572300D01*
X380742Y572383D01*
X380409Y572300D01*
X380200Y572050D01*
X380075Y571758D01*
Y570717D01*
G01Y571758D02*
X378867Y572383D01*
G01Y575150D02*
X381367D01*
X379575Y573608D01*
Y575692D01*
G01X380950Y576958D02*
X381200Y577208D01*
X381325Y577500D01*
X381367Y577833D01*
X381284Y578250D01*
X381075Y578542D01*
X380825Y578625D01*
X380575Y578583D01*
X380367Y578417D01*
X379950Y577583D01*
X379659Y577208D01*
X379242Y576958D01*
X378867Y576875D01*
Y578625D01*
G01X379242Y579933D02*
X379034Y580183D01*
X378909Y580475D01*
X378867Y580850D01*
X378950Y581225D01*
X379117Y581517D01*
X379409Y581725D01*
X379742Y581767D01*
X380075Y581683D01*
X380284Y581475D01*
X380450Y581183D01*
X380492Y580892D01*
X380450Y580600D01*
X380284Y580225D01*
X381367Y580350D01*
Y581475D01*
G01X360300Y572900D02*
Y576900D01*
X367700D01*
G01X386967Y596367D02*
X389467D01*
Y597408D01*
X389342Y597742D01*
X389175Y597950D01*
X388842Y598033D01*
X388509Y597950D01*
X388300Y597700D01*
X388175Y597408D01*
Y596367D01*
G01Y597408D02*
X386967Y598033D01*
G01Y600800D02*
X389467D01*
X387675Y599258D01*
Y601342D01*
G01X389050Y602608D02*
X389300Y602858D01*
X389425Y603150D01*
X389467Y603483D01*
X389384Y603900D01*
X389175Y604192D01*
X388925Y604275D01*
X388675Y604233D01*
X388467Y604067D01*
X388050Y603233D01*
X387759Y602858D01*
X387342Y602608D01*
X386967Y602525D01*
Y604275D01*
G01X382000Y596400D02*
X378000D01*
Y603800D01*
G01X390700Y613267D02*
Y610767D01*
G01X391658Y613267D02*
X389742D01*
G01X388433Y610767D02*
Y613267D01*
X387433D01*
X387100Y613142D01*
X386850Y612850D01*
X386767Y612517D01*
X386850Y612184D01*
X387058Y611934D01*
X387433Y611809D01*
X388433D01*
G01X385292D02*
X385000Y612100D01*
X384750Y612267D01*
X384417Y612350D01*
X384125Y612267D01*
X383917Y612100D01*
X383750Y611850D01*
X383708Y611559D01*
X383750Y611309D01*
X383917Y611059D01*
X384167Y610850D01*
X384458Y610767D01*
X384792Y610850D01*
X385083Y611100D01*
X385250Y611475D01*
X385292Y611892D01*
X385208Y612434D01*
X385083Y612725D01*
X384875Y613017D01*
X384583Y613225D01*
X384292Y613267D01*
X384000Y613184D01*
X383792Y612975D01*
G01X360200Y570000D02*
X374200D01*
G01X378792Y635867D02*
X378917Y635617D01*
X379000Y635325D01*
Y634992D01*
X378875Y634617D01*
X378667Y634325D01*
X378417Y634117D01*
X378000Y633950D01*
X377625Y633908D01*
X377250Y633992D01*
X377000Y634117D01*
X376750Y634367D01*
X376583Y634658D01*
X376500Y634950D01*
Y635242D01*
X376583Y635533D01*
X376708Y635783D01*
X376875Y635992D01*
G01X376500Y638050D02*
X376542Y638342D01*
X376667Y638675D01*
X376875Y638883D01*
X377167Y638967D01*
X377458Y638883D01*
X377708Y638633D01*
X377833Y638258D01*
Y637842D01*
X377917Y637592D01*
X378125Y637383D01*
X378417Y637300D01*
X378708Y637425D01*
X378917Y637717D01*
X379000Y638050D01*
X378917Y638383D01*
X378708Y638675D01*
X378417Y638800D01*
X378125Y638717D01*
X377917Y638508D01*
X377833Y638258D01*
Y637842D01*
X377708Y637467D01*
X377458Y637217D01*
X377167Y637133D01*
X376875Y637217D01*
X376667Y637425D01*
X376542Y637758D01*
X376500Y638050D01*
G01X385259Y598117D02*
X385384Y597867D01*
X385467Y597575D01*
Y597242D01*
X385342Y596867D01*
X385134Y596575D01*
X384884Y596367D01*
X384467Y596200D01*
X384092Y596158D01*
X383717Y596242D01*
X383467Y596367D01*
X383217Y596617D01*
X383050Y596908D01*
X382967Y597200D01*
Y597492D01*
X383050Y597783D01*
X383175Y598033D01*
X383342Y598242D01*
G01X382967Y600300D02*
X385467D01*
X384967Y599800D01*
G01X382967D02*
Y600800D01*
G01X383467Y602483D02*
X383175Y602733D01*
X383009Y603067D01*
X382967Y603442D01*
X383009Y603775D01*
X383217Y604108D01*
X383467Y604317D01*
X383717Y604358D01*
X384009Y604275D01*
X384217Y603983D01*
X384300Y603692D01*
Y603317D01*
G01Y603692D02*
X384425Y603942D01*
X384634Y604150D01*
X384884Y604233D01*
X385134Y604150D01*
X385342Y603942D01*
X385467Y603567D01*
X385425Y603192D01*
X385259Y602817D01*
G01X372292Y599867D02*
X372417Y599617D01*
X372500Y599325D01*
Y598992D01*
X372375Y598617D01*
X372167Y598325D01*
X371917Y598117D01*
X371500Y597950D01*
X371125Y597908D01*
X370750Y597992D01*
X370500Y598117D01*
X370250Y598367D01*
X370083Y598658D01*
X370000Y598950D01*
Y599242D01*
X370083Y599533D01*
X370208Y599783D01*
X370375Y599992D01*
G01X370292Y601342D02*
X370083Y601633D01*
X370000Y601967D01*
X370083Y602300D01*
X370333Y602592D01*
X370708Y602800D01*
X371083Y602883D01*
X371542D01*
X371917Y602800D01*
X372250Y602592D01*
X372417Y602342D01*
X372500Y602050D01*
X372417Y601717D01*
X372250Y601467D01*
X372000Y601300D01*
X371667Y601217D01*
X371375Y601300D01*
X371083Y601508D01*
X370917Y601758D01*
X370875Y602050D01*
X370958Y602383D01*
X371167Y602633D01*
X371542Y602883D01*
G01X368652Y632739D02*
X368777Y632489D01*
X368860Y632197D01*
Y631864D01*
X368735Y631489D01*
X368527Y631197D01*
X368277Y630989D01*
X367860Y630822D01*
X367485Y630780D01*
X367110Y630864D01*
X366860Y630989D01*
X366610Y631239D01*
X366443Y631530D01*
X366360Y631822D01*
Y632114D01*
X366443Y632405D01*
X366568Y632655D01*
X366735Y632864D01*
G01X366360Y634922D02*
X368860D01*
X368360Y634422D01*
G01X366360D02*
Y635422D01*
G01Y638022D02*
X368860D01*
X368360Y637522D01*
G01X366360D02*
Y638522D01*
G01X376783Y657600D02*
Y660100D01*
X375742D01*
X375408Y659975D01*
X375200Y659808D01*
X375117Y659475D01*
X375200Y659142D01*
X375450Y658933D01*
X375742Y658808D01*
X376783D01*
G01X375742D02*
X375117Y657600D01*
G01X372350D02*
Y660100D01*
X373892Y658308D01*
X371808D01*
G01X369750Y657600D02*
Y660100D01*
X370250Y659600D01*
G01Y657600D02*
X369250D01*
G01X367358Y657892D02*
X367067Y657683D01*
X366733Y657600D01*
X366400Y657683D01*
X366108Y657933D01*
X365900Y658308D01*
X365817Y658683D01*
Y659142D01*
X365900Y659517D01*
X366108Y659850D01*
X366358Y660017D01*
X366650Y660100D01*
X366983Y660017D01*
X367233Y659850D01*
X367400Y659600D01*
X367483Y659267D01*
X367400Y658975D01*
X367192Y658683D01*
X366942Y658517D01*
X366650Y658475D01*
X366317Y658558D01*
X366067Y658767D01*
X365817Y659142D01*
G01X377530Y672867D02*
Y675367D01*
X376489D01*
X376155Y675242D01*
X375947Y675075D01*
X375864Y674742D01*
X375947Y674409D01*
X376197Y674200D01*
X376489Y674075D01*
X377530D01*
G01X376489D02*
X375864Y672867D01*
G01X373097D02*
Y675367D01*
X374639Y673575D01*
X372555D01*
G01X370497Y672867D02*
Y675367D01*
X370997Y674867D01*
G01Y672867D02*
X369997D01*
G01X367397D02*
X367105Y672909D01*
X366772Y673034D01*
X366564Y673242D01*
X366480Y673534D01*
X366564Y673825D01*
X366814Y674075D01*
X367189Y674200D01*
X367605D01*
X367855Y674284D01*
X368064Y674492D01*
X368147Y674784D01*
X368022Y675075D01*
X367730Y675284D01*
X367397Y675367D01*
X367064Y675284D01*
X366772Y675075D01*
X366647Y674784D01*
X366730Y674492D01*
X366939Y674284D01*
X367189Y674200D01*
X367605D01*
X367980Y674075D01*
X368230Y673825D01*
X368314Y673534D01*
X368230Y673242D01*
X368022Y673034D01*
X367689Y672909D01*
X367397Y672867D01*
G01X376530Y661667D02*
Y664167D01*
X375489D01*
X375155Y664042D01*
X374947Y663875D01*
X374864Y663542D01*
X374947Y663209D01*
X375197Y663000D01*
X375489Y662875D01*
X376530D01*
G01X375489D02*
X374864Y661667D01*
G01X372680D02*
X372597Y662209D01*
X372472Y662667D01*
X372305Y663084D01*
X372097Y663542D01*
X371764Y664167D01*
X373430D01*
G01X370205Y661959D02*
X369914Y661750D01*
X369580Y661667D01*
X369247Y661750D01*
X368955Y662000D01*
X368747Y662375D01*
X368664Y662750D01*
Y663209D01*
X368747Y663584D01*
X368955Y663917D01*
X369205Y664084D01*
X369497Y664167D01*
X369830Y664084D01*
X370080Y663917D01*
X370247Y663667D01*
X370330Y663334D01*
X370247Y663042D01*
X370039Y662750D01*
X369789Y662584D01*
X369497Y662542D01*
X369164Y662625D01*
X368914Y662834D01*
X368664Y663209D01*
G01X367314Y662042D02*
X367064Y661834D01*
X366772Y661709D01*
X366397Y661667D01*
X366022Y661750D01*
X365730Y661917D01*
X365522Y662209D01*
X365480Y662542D01*
X365564Y662875D01*
X365772Y663084D01*
X366064Y663250D01*
X366355Y663292D01*
X366647Y663250D01*
X367022Y663084D01*
X366897Y664167D01*
X365772D01*
G01X462543Y19957D02*
Y22457D01*
X461502D01*
X461168Y22332D01*
X460960Y22165D01*
X460877Y21832D01*
X460960Y21499D01*
X461210Y21290D01*
X461502Y21165D01*
X462543D01*
G01X461502D02*
X460877Y19957D01*
G01X458110D02*
Y22457D01*
X459652Y20665D01*
X457568D01*
G01X456427Y20457D02*
X456177Y20165D01*
X455843Y19999D01*
X455468Y19957D01*
X455135Y19999D01*
X454802Y20207D01*
X454593Y20457D01*
X454552Y20707D01*
X454635Y20999D01*
X454927Y21207D01*
X455218Y21290D01*
X455593D01*
G01X455218D02*
X454968Y21415D01*
X454760Y21624D01*
X454677Y21874D01*
X454760Y22124D01*
X454968Y22332D01*
X455343Y22457D01*
X455718Y22415D01*
X456093Y22249D01*
G01X453202Y20999D02*
X452910Y21290D01*
X452660Y21457D01*
X452327Y21540D01*
X452035Y21457D01*
X451827Y21290D01*
X451660Y21040D01*
X451618Y20749D01*
X451660Y20499D01*
X451827Y20249D01*
X452077Y20040D01*
X452368Y19957D01*
X452702Y20040D01*
X452993Y20290D01*
X453160Y20665D01*
X453202Y21082D01*
X453118Y21624D01*
X452993Y21915D01*
X452785Y22207D01*
X452493Y22415D01*
X452202Y22457D01*
X451910Y22374D01*
X451702Y22165D01*
G01X456260Y23990D02*
Y27990D01*
X463660D01*
G01X509499Y35096D02*
Y37596D01*
X508458D01*
X508124Y37471D01*
X507916Y37304D01*
X507833Y36971D01*
X507916Y36638D01*
X508166Y36429D01*
X508458Y36304D01*
X509499D01*
G01X508458D02*
X507833Y35096D01*
G01X505066D02*
Y37596D01*
X506608Y35804D01*
X504524D01*
G01X503383Y35596D02*
X503133Y35304D01*
X502799Y35138D01*
X502424Y35096D01*
X502091Y35138D01*
X501758Y35346D01*
X501549Y35596D01*
X501508Y35846D01*
X501591Y36138D01*
X501883Y36346D01*
X502174Y36429D01*
X502549D01*
G01X502174D02*
X501924Y36554D01*
X501716Y36763D01*
X501633Y37013D01*
X501716Y37263D01*
X501924Y37471D01*
X502299Y37596D01*
X502674Y37554D01*
X503049Y37388D01*
G01X499449Y35096D02*
X499366Y35638D01*
X499241Y36096D01*
X499074Y36513D01*
X498866Y36971D01*
X498533Y37596D01*
X500199D01*
G01X499218Y44607D02*
Y40607D01*
X491818D01*
G01X491500Y69300D02*
X495500D01*
Y61900D01*
G01X509499Y31096D02*
Y33596D01*
X508458D01*
X508124Y33471D01*
X507916Y33304D01*
X507833Y32971D01*
X507916Y32638D01*
X508166Y32429D01*
X508458Y32304D01*
X509499D01*
G01X508458D02*
X507833Y31096D01*
G01X505066D02*
Y33596D01*
X506608Y31804D01*
X504524D01*
G01X501966Y31096D02*
Y33596D01*
X503508Y31804D01*
X501424D01*
G01X500074Y31388D02*
X499783Y31179D01*
X499449Y31096D01*
X499116Y31179D01*
X498824Y31429D01*
X498616Y31804D01*
X498533Y32179D01*
Y32638D01*
X498616Y33013D01*
X498824Y33346D01*
X499074Y33513D01*
X499366Y33596D01*
X499699Y33513D01*
X499949Y33346D01*
X500116Y33096D01*
X500199Y32763D01*
X500116Y32471D01*
X499908Y32179D01*
X499658Y32013D01*
X499366Y31971D01*
X499033Y32054D01*
X498783Y32263D01*
X498533Y32638D01*
G01X488260Y35883D02*
Y39883D01*
X495660D01*
G01X483536Y52350D02*
X486036D01*
Y53391D01*
X485911Y53725D01*
X485744Y53933D01*
X485411Y54016D01*
X485078Y53933D01*
X484869Y53683D01*
X484744Y53391D01*
Y52350D01*
G01Y53391D02*
X483536Y54016D01*
G01Y56783D02*
X486036D01*
X484244Y55241D01*
Y57325D01*
G01X483536Y59883D02*
X486036D01*
X484244Y58341D01*
Y60425D01*
G01X483536Y62400D02*
X484078Y62483D01*
X484536Y62608D01*
X484953Y62775D01*
X485411Y62983D01*
X486036Y63316D01*
Y61650D01*
G01X496150Y60730D02*
X500150D01*
Y53330D01*
G01X509499Y27096D02*
Y29596D01*
X508458D01*
X508124Y29471D01*
X507916Y29304D01*
X507833Y28971D01*
X507916Y28638D01*
X508166Y28429D01*
X508458Y28304D01*
X509499D01*
G01X508458D02*
X507833Y27096D01*
G01X505066D02*
Y29596D01*
X506608Y27804D01*
X504524D01*
G01X503383Y27596D02*
X503133Y27304D01*
X502799Y27138D01*
X502424Y27096D01*
X502091Y27138D01*
X501758Y27346D01*
X501549Y27596D01*
X501508Y27846D01*
X501591Y28138D01*
X501883Y28346D01*
X502174Y28429D01*
X502549D01*
G01X502174D02*
X501924Y28554D01*
X501716Y28763D01*
X501633Y29013D01*
X501716Y29263D01*
X501924Y29471D01*
X502299Y29596D01*
X502674Y29554D01*
X503049Y29388D01*
G01X500283Y27596D02*
X500033Y27304D01*
X499699Y27138D01*
X499324Y27096D01*
X498991Y27138D01*
X498658Y27346D01*
X498449Y27596D01*
X498408Y27846D01*
X498491Y28138D01*
X498783Y28346D01*
X499074Y28429D01*
X499449D01*
G01X499074D02*
X498824Y28554D01*
X498616Y28763D01*
X498533Y29013D01*
X498616Y29263D01*
X498824Y29471D01*
X499199Y29596D01*
X499574Y29554D01*
X499949Y29388D01*
G01X495650Y35781D02*
Y31781D01*
X488250D01*
G01X453300Y31727D02*
X455800D01*
Y32768D01*
X455675Y33102D01*
X455508Y33310D01*
X455175Y33393D01*
X454842Y33310D01*
X454633Y33060D01*
X454508Y32768D01*
Y31727D01*
G01Y32768D02*
X453300Y33393D01*
G01X453675Y34743D02*
X453467Y34993D01*
X453342Y35285D01*
X453300Y35660D01*
X453383Y36035D01*
X453550Y36327D01*
X453842Y36535D01*
X454175Y36577D01*
X454508Y36493D01*
X454717Y36285D01*
X454883Y35993D01*
X454925Y35702D01*
X454883Y35410D01*
X454717Y35035D01*
X455800Y35160D01*
Y36285D01*
G01X455383Y37968D02*
X455633Y38218D01*
X455758Y38510D01*
X455800Y38843D01*
X455717Y39260D01*
X455508Y39552D01*
X455258Y39635D01*
X455008Y39593D01*
X454800Y39427D01*
X454383Y38593D01*
X454092Y38218D01*
X453675Y37968D01*
X453300Y37885D01*
Y39635D01*
G01Y42360D02*
X455800D01*
X454008Y40818D01*
Y42902D01*
G01X457610Y39040D02*
X461610D01*
Y31640D01*
G01X481798Y53810D02*
X481923Y53560D01*
X482006Y53268D01*
Y52935D01*
X481881Y52560D01*
X481673Y52268D01*
X481423Y52060D01*
X481006Y51893D01*
X480631Y51851D01*
X480256Y51935D01*
X480006Y52060D01*
X479756Y52310D01*
X479589Y52601D01*
X479506Y52893D01*
Y53185D01*
X479589Y53476D01*
X479714Y53726D01*
X479881Y53935D01*
G01X479506Y55993D02*
X482006D01*
X481506Y55493D01*
G01X479506D02*
Y56493D01*
G01Y59593D02*
X482006D01*
X480214Y58051D01*
Y60135D01*
G01X479506Y62693D02*
X482006D01*
X480214Y61151D01*
Y63235D01*
G01X447959Y18767D02*
X448084Y18517D01*
X448167Y18225D01*
Y17892D01*
X448042Y17517D01*
X447834Y17225D01*
X447584Y17017D01*
X447167Y16850D01*
X446792Y16808D01*
X446417Y16892D01*
X446167Y17017D01*
X445917Y17267D01*
X445750Y17558D01*
X445667Y17850D01*
Y18142D01*
X445750Y18433D01*
X445875Y18683D01*
X446042Y18892D01*
G01X445667Y20950D02*
X448167D01*
X447667Y20450D01*
G01X445667D02*
Y21450D01*
G01X446042Y23133D02*
X445834Y23383D01*
X445709Y23675D01*
X445667Y24050D01*
X445750Y24425D01*
X445917Y24717D01*
X446209Y24925D01*
X446542Y24967D01*
X446875Y24883D01*
X447084Y24675D01*
X447250Y24383D01*
X447292Y24092D01*
X447250Y23800D01*
X447084Y23425D01*
X448167Y23550D01*
Y24675D01*
G01Y27150D02*
X448084Y26817D01*
X447875Y26567D01*
X447625Y26400D01*
X447292Y26275D01*
X446917Y26233D01*
X446542Y26275D01*
X446209Y26400D01*
X445959Y26567D01*
X445750Y26817D01*
X445667Y27150D01*
X445750Y27483D01*
X445959Y27733D01*
X446209Y27900D01*
X446542Y28025D01*
X446917Y28067D01*
X447292Y28025D01*
X447625Y27900D01*
X447875Y27733D01*
X448084Y27483D01*
X448167Y27150D01*
G01X472959Y39721D02*
X473084Y39471D01*
X473167Y39179D01*
Y38846D01*
X473042Y38471D01*
X472834Y38179D01*
X472584Y37971D01*
X472167Y37804D01*
X471792Y37762D01*
X471417Y37846D01*
X471167Y37971D01*
X470917Y38221D01*
X470750Y38512D01*
X470667Y38804D01*
Y39096D01*
X470750Y39387D01*
X470875Y39637D01*
X471042Y39846D01*
G01X470667Y40862D02*
X473167Y41904D01*
X470667Y42946D01*
G01X471542Y42571D02*
Y41237D01*
G01X470667Y45004D02*
X473167D01*
X472667Y44504D01*
G01X470667D02*
Y45504D01*
G01X476733Y18259D02*
X476983Y18384D01*
X477275Y18467D01*
X477608D01*
X477983Y18342D01*
X478275Y18134D01*
X478483Y17884D01*
X478650Y17467D01*
X478692Y17092D01*
X478608Y16717D01*
X478483Y16467D01*
X478233Y16217D01*
X477942Y16050D01*
X477650Y15967D01*
X477358D01*
X477067Y16050D01*
X476817Y16175D01*
X476608Y16342D01*
G01X474550Y15967D02*
Y18467D01*
X475050Y17967D01*
G01Y15967D02*
X474050D01*
G01X472367Y16467D02*
X472117Y16175D01*
X471783Y16009D01*
X471408Y15967D01*
X471075Y16009D01*
X470742Y16217D01*
X470533Y16467D01*
X470492Y16717D01*
X470575Y17009D01*
X470867Y17217D01*
X471158Y17300D01*
X471533D01*
G01X471158D02*
X470908Y17425D01*
X470700Y17634D01*
X470617Y17884D01*
X470700Y18134D01*
X470908Y18342D01*
X471283Y18467D01*
X471658Y18425D01*
X472033Y18259D01*
G01X469142Y18050D02*
X468892Y18300D01*
X468600Y18425D01*
X468267Y18467D01*
X467850Y18384D01*
X467558Y18175D01*
X467475Y17925D01*
X467517Y17675D01*
X467683Y17467D01*
X468517Y17050D01*
X468892Y16759D01*
X469142Y16342D01*
X469225Y15967D01*
X467475D01*
G01X476229Y21800D02*
X481729D01*
Y29800D01*
X476129D01*
G01X464129Y21800D02*
X469629D01*
G01X464129D02*
Y29800D01*
X469629D01*
G01X440983Y41667D02*
Y44167D01*
X439942D01*
X439608Y44042D01*
X439400Y43875D01*
X439317Y43542D01*
X439400Y43209D01*
X439650Y43000D01*
X439942Y42875D01*
X440983D01*
G01X439942D02*
X439317Y41667D01*
G01X436550D02*
Y44167D01*
X438092Y42375D01*
X436008D01*
G01X434742Y42709D02*
X434450Y43000D01*
X434200Y43167D01*
X433867Y43250D01*
X433575Y43167D01*
X433367Y43000D01*
X433200Y42750D01*
X433158Y42459D01*
X433200Y42209D01*
X433367Y41959D01*
X433617Y41750D01*
X433908Y41667D01*
X434242Y41750D01*
X434533Y42000D01*
X434700Y42375D01*
X434742Y42792D01*
X434658Y43334D01*
X434533Y43625D01*
X434325Y43917D01*
X434033Y44125D01*
X433742Y44167D01*
X433450Y44084D01*
X433242Y43875D01*
G01X430850Y41667D02*
Y44167D01*
X431350Y43667D01*
G01Y41667D02*
X430350D01*
G01X436000Y35800D02*
Y39800D01*
X443400D01*
G01X489399Y65092D02*
Y67592D01*
X488358D01*
X488024Y67467D01*
X487816Y67300D01*
X487733Y66967D01*
X487816Y66634D01*
X488066Y66425D01*
X488358Y66300D01*
X489399D01*
G01X488358D02*
X487733Y65092D01*
G01X484966D02*
Y67592D01*
X486508Y65800D01*
X484424D01*
G01X481866Y65092D02*
Y67592D01*
X483408Y65800D01*
X481324D01*
G01X480183Y65467D02*
X479933Y65259D01*
X479641Y65134D01*
X479266Y65092D01*
X478891Y65175D01*
X478599Y65342D01*
X478391Y65634D01*
X478349Y65967D01*
X478433Y66300D01*
X478641Y66509D01*
X478933Y66675D01*
X479224Y66717D01*
X479516Y66675D01*
X479891Y66509D01*
X479766Y67592D01*
X478641D01*
G01X510670Y40417D02*
X513170D01*
Y41458D01*
X513045Y41792D01*
X512878Y42000D01*
X512545Y42083D01*
X512212Y42000D01*
X512003Y41750D01*
X511878Y41458D01*
Y40417D01*
G01Y41458D02*
X510670Y42083D01*
G01Y44850D02*
X513170D01*
X511378Y43308D01*
Y45392D01*
G01X510670Y47950D02*
X513170D01*
X511378Y46408D01*
Y48492D01*
G01X510670Y50550D02*
X510712Y50842D01*
X510837Y51175D01*
X511045Y51383D01*
X511337Y51467D01*
X511628Y51383D01*
X511878Y51133D01*
X512003Y50758D01*
Y50342D01*
X512087Y50092D01*
X512295Y49883D01*
X512587Y49800D01*
X512878Y49925D01*
X513087Y50217D01*
X513170Y50550D01*
X513087Y50883D01*
X512878Y51175D01*
X512587Y51300D01*
X512295Y51217D01*
X512087Y51008D01*
X512003Y50758D01*
Y50342D01*
X511878Y49967D01*
X511628Y49717D01*
X511337Y49633D01*
X511045Y49717D01*
X510837Y49925D01*
X510712Y50258D01*
X510670Y50550D01*
G01X509500Y60200D02*
X513500D01*
Y52800D01*
G01X528650Y75140D02*
Y61140D01*
G01X515650D02*
Y75140D01*
G01X528650Y61140D02*
X515650D01*
G01X504952Y41897D02*
X505077Y41647D01*
X505160Y41355D01*
Y41022D01*
X505035Y40647D01*
X504827Y40355D01*
X504577Y40147D01*
X504160Y39980D01*
X503785Y39938D01*
X503410Y40022D01*
X503160Y40147D01*
X502910Y40397D01*
X502743Y40688D01*
X502660Y40980D01*
Y41272D01*
X502743Y41563D01*
X502868Y41813D01*
X503035Y42022D01*
G01X502660Y44080D02*
X505160D01*
X504660Y43580D01*
G01X502660D02*
Y44580D01*
G01Y47680D02*
X505160D01*
X503368Y46138D01*
Y48222D01*
G01X503035Y49363D02*
X502827Y49613D01*
X502702Y49905D01*
X502660Y50280D01*
X502743Y50655D01*
X502910Y50947D01*
X503202Y51155D01*
X503535Y51197D01*
X503868Y51113D01*
X504077Y50905D01*
X504243Y50613D01*
X504285Y50322D01*
X504243Y50030D01*
X504077Y49655D01*
X505160Y49780D01*
Y50905D01*
G01X514413Y68460D02*
Y70960D01*
X513372D01*
X513038Y70835D01*
X512830Y70668D01*
X512747Y70335D01*
X512830Y70002D01*
X513080Y69793D01*
X513372Y69668D01*
X514413D01*
G01X513372D02*
X512747Y68460D01*
G01X509980D02*
Y70960D01*
X511522Y69168D01*
X509438D01*
G01X506880Y68460D02*
Y70960D01*
X508422Y69168D01*
X506338D01*
G01X505072Y69502D02*
X504780Y69793D01*
X504530Y69960D01*
X504197Y70043D01*
X503905Y69960D01*
X503697Y69793D01*
X503530Y69543D01*
X503488Y69252D01*
X503530Y69002D01*
X503697Y68752D01*
X503947Y68543D01*
X504238Y68460D01*
X504572Y68543D01*
X504863Y68793D01*
X505030Y69168D01*
X505072Y69585D01*
X504988Y70127D01*
X504863Y70418D01*
X504655Y70710D01*
X504363Y70918D01*
X504072Y70960D01*
X503780Y70877D01*
X503572Y70668D01*
G01X512700Y67000D02*
Y63000D01*
X505300D01*
G01X514870Y82017D02*
X517370D01*
Y83058D01*
X517245Y83392D01*
X517078Y83600D01*
X516745Y83683D01*
X516412Y83600D01*
X516203Y83350D01*
X516078Y83058D01*
Y82017D01*
G01Y83058D02*
X514870Y83683D01*
G01Y85867D02*
X515412Y85950D01*
X515870Y86075D01*
X516287Y86242D01*
X516745Y86450D01*
X517370Y86783D01*
Y85117D01*
G01X514870Y89550D02*
X517370D01*
X515578Y88008D01*
Y90092D01*
G01X514870Y92650D02*
X517370D01*
X515578Y91108D01*
Y93192D01*
G01X523330Y80180D02*
X519330D01*
Y87580D01*
G01X539483Y77000D02*
Y79500D01*
X538442D01*
X538108Y79375D01*
X537900Y79208D01*
X537817Y78875D01*
X537900Y78542D01*
X538150Y78333D01*
X538442Y78208D01*
X539483D01*
G01X538442D02*
X537817Y77000D01*
G01X535633D02*
X535550Y77542D01*
X535425Y78000D01*
X535258Y78417D01*
X535050Y78875D01*
X534717Y79500D01*
X536383D01*
G01X531950Y77000D02*
Y79500D01*
X533492Y77708D01*
X531408D01*
G01X530267Y77500D02*
X530017Y77208D01*
X529683Y77042D01*
X529308Y77000D01*
X528975Y77042D01*
X528642Y77250D01*
X528433Y77500D01*
X528392Y77750D01*
X528475Y78042D01*
X528767Y78250D01*
X529058Y78333D01*
X529433D01*
G01X529058D02*
X528808Y78458D01*
X528600Y78667D01*
X528517Y78917D01*
X528600Y79167D01*
X528808Y79375D01*
X529183Y79500D01*
X529558Y79458D01*
X529933Y79292D01*
G01X515890Y75700D02*
Y79700D01*
X523290D01*
G01X545483Y71500D02*
Y74000D01*
X544442D01*
X544108Y73875D01*
X543900Y73708D01*
X543817Y73375D01*
X543900Y73042D01*
X544150Y72833D01*
X544442Y72708D01*
X545483D01*
G01X544442D02*
X543817Y71500D01*
G01X541633D02*
X541550Y72042D01*
X541425Y72500D01*
X541258Y72917D01*
X541050Y73375D01*
X540717Y74000D01*
X542383D01*
G01X537950Y71500D02*
Y74000D01*
X539492Y72208D01*
X537408D01*
G01X536142Y73583D02*
X535892Y73833D01*
X535600Y73958D01*
X535267Y74000D01*
X534850Y73917D01*
X534558Y73708D01*
X534475Y73458D01*
X534517Y73208D01*
X534683Y73000D01*
X535517Y72583D01*
X535892Y72292D01*
X536142Y71875D01*
X536225Y71500D01*
X534475D01*
G01X540406Y70742D02*
Y66742D01*
X533006D01*
G01X530000Y68400D02*
X530042Y68067D01*
X530208Y67775D01*
X530458Y67525D01*
X530750Y67358D01*
X531083Y67275D01*
X531417D01*
X531750Y67358D01*
X532042Y67525D01*
X532292Y67775D01*
X532458Y68067D01*
X532500Y68400D01*
X532458Y68733D01*
X532292Y69025D01*
X532042Y69275D01*
X531750Y69442D01*
X531417Y69525D01*
X531083D01*
X530750Y69442D01*
X530458Y69275D01*
X530208Y69025D01*
X530042Y68733D01*
X530000Y68400D01*
G01X530667Y68733D02*
X530000Y69233D01*
G01X532083Y70708D02*
X532333Y70958D01*
X532458Y71250D01*
X532500Y71583D01*
X532417Y72000D01*
X532208Y72292D01*
X531958Y72375D01*
X531708Y72333D01*
X531500Y72167D01*
X531083Y71333D01*
X530792Y70958D01*
X530375Y70708D01*
X530000Y70625D01*
Y72375D01*
G01Y75100D02*
X532500D01*
X530708Y73558D01*
Y75642D01*
G01X515650Y75140D02*
X528650D01*
G01X582542Y55618D02*
X582667Y55368D01*
X582750Y55076D01*
Y54743D01*
X582625Y54368D01*
X582417Y54076D01*
X582167Y53868D01*
X581750Y53701D01*
X581375Y53659D01*
X581000Y53743D01*
X580750Y53868D01*
X580500Y54118D01*
X580333Y54409D01*
X580250Y54701D01*
Y54993D01*
X580333Y55284D01*
X580458Y55534D01*
X580625Y55743D01*
G01X582333Y57009D02*
X582583Y57259D01*
X582708Y57551D01*
X582750Y57884D01*
X582667Y58301D01*
X582458Y58593D01*
X582208Y58676D01*
X581958Y58634D01*
X581750Y58468D01*
X581333Y57634D01*
X581042Y57259D01*
X580625Y57009D01*
X580250Y56926D01*
Y58676D01*
G01Y60901D02*
X582750D01*
X582250Y60401D01*
G01X580250D02*
Y61401D01*
G01X582333Y63209D02*
X582583Y63459D01*
X582708Y63751D01*
X582750Y64084D01*
X582667Y64501D01*
X582458Y64793D01*
X582208Y64876D01*
X581958Y64834D01*
X581750Y64668D01*
X581333Y63834D01*
X581042Y63459D01*
X580625Y63209D01*
X580250Y63126D01*
Y64876D01*
G01X665425Y14753D02*
X665550Y14503D01*
X665633Y14211D01*
Y13878D01*
X665508Y13503D01*
X665300Y13211D01*
X665050Y13003D01*
X664633Y12836D01*
X664258Y12794D01*
X663883Y12878D01*
X663633Y13003D01*
X663383Y13253D01*
X663216Y13544D01*
X663133Y13836D01*
Y14128D01*
X663216Y14419D01*
X663341Y14669D01*
X663508Y14878D01*
G01X665216Y16144D02*
X665466Y16394D01*
X665591Y16686D01*
X665633Y17019D01*
X665550Y17436D01*
X665341Y17728D01*
X665091Y17811D01*
X664841Y17769D01*
X664633Y17603D01*
X664216Y16769D01*
X663925Y16394D01*
X663508Y16144D01*
X663133Y16061D01*
Y17811D01*
G01Y20036D02*
X665633D01*
X665133Y19536D01*
G01X663133D02*
Y20536D01*
G01X663508Y22219D02*
X663300Y22469D01*
X663175Y22761D01*
X663133Y23136D01*
X663216Y23511D01*
X663383Y23803D01*
X663675Y24011D01*
X664008Y24053D01*
X664341Y23969D01*
X664550Y23761D01*
X664716Y23469D01*
X664758Y23178D01*
X664716Y22886D01*
X664550Y22511D01*
X665633Y22636D01*
Y23761D01*
G01X657425Y14753D02*
X657550Y14503D01*
X657633Y14211D01*
Y13878D01*
X657508Y13503D01*
X657300Y13211D01*
X657050Y13003D01*
X656633Y12836D01*
X656258Y12794D01*
X655883Y12878D01*
X655633Y13003D01*
X655383Y13253D01*
X655216Y13544D01*
X655133Y13836D01*
Y14128D01*
X655216Y14419D01*
X655341Y14669D01*
X655508Y14878D01*
G01X657216Y16144D02*
X657466Y16394D01*
X657591Y16686D01*
X657633Y17019D01*
X657550Y17436D01*
X657341Y17728D01*
X657091Y17811D01*
X656841Y17769D01*
X656633Y17603D01*
X656216Y16769D01*
X655925Y16394D01*
X655508Y16144D01*
X655133Y16061D01*
Y17811D01*
G01Y20036D02*
X657633D01*
X657133Y19536D01*
G01X655133D02*
Y20536D01*
G01Y23136D02*
X655175Y23428D01*
X655300Y23761D01*
X655508Y23969D01*
X655800Y24053D01*
X656091Y23969D01*
X656341Y23719D01*
X656466Y23344D01*
Y22928D01*
X656550Y22678D01*
X656758Y22469D01*
X657050Y22386D01*
X657341Y22511D01*
X657550Y22803D01*
X657633Y23136D01*
X657550Y23469D01*
X657341Y23761D01*
X657050Y23886D01*
X656758Y23803D01*
X656550Y23594D01*
X656466Y23344D01*
Y22928D01*
X656341Y22553D01*
X656091Y22303D01*
X655800Y22219D01*
X655508Y22303D01*
X655300Y22511D01*
X655175Y22844D01*
X655133Y23136D01*
G01X669796Y469781D02*
X670046Y469906D01*
X670338Y469989D01*
X670671D01*
X671046Y469864D01*
X671338Y469656D01*
X671546Y469406D01*
X671713Y468989D01*
X671755Y468614D01*
X671671Y468239D01*
X671546Y467989D01*
X671296Y467739D01*
X671005Y467572D01*
X670713Y467489D01*
X670421D01*
X670130Y467572D01*
X669880Y467697D01*
X669671Y467864D01*
G01X668405Y468531D02*
X668113Y468822D01*
X667863Y468989D01*
X667530Y469072D01*
X667238Y468989D01*
X667030Y468822D01*
X666863Y468572D01*
X666821Y468281D01*
X666863Y468031D01*
X667030Y467781D01*
X667280Y467572D01*
X667571Y467489D01*
X667905Y467572D01*
X668196Y467822D01*
X668363Y468197D01*
X668405Y468614D01*
X668321Y469156D01*
X668196Y469447D01*
X667988Y469739D01*
X667696Y469947D01*
X667405Y469989D01*
X667113Y469906D01*
X666905Y469697D01*
G01X664513Y467489D02*
Y469989D01*
X665013Y469489D01*
G01Y467489D02*
X664013D01*
G01X661413D02*
X661121Y467531D01*
X660788Y467656D01*
X660580Y467864D01*
X660496Y468156D01*
X660580Y468447D01*
X660830Y468697D01*
X661205Y468822D01*
X661621D01*
X661871Y468906D01*
X662080Y469114D01*
X662163Y469406D01*
X662038Y469697D01*
X661746Y469906D01*
X661413Y469989D01*
X661080Y469906D01*
X660788Y469697D01*
X660663Y469406D01*
X660746Y469114D01*
X660955Y468906D01*
X661205Y468822D01*
X661621D01*
X661996Y468697D01*
X662246Y468447D01*
X662330Y468156D01*
X662246Y467864D01*
X662038Y467656D01*
X661705Y467531D01*
X661413Y467489D01*
G01X669796Y473781D02*
X670046Y473906D01*
X670338Y473989D01*
X670671D01*
X671046Y473864D01*
X671338Y473656D01*
X671546Y473406D01*
X671713Y472989D01*
X671755Y472614D01*
X671671Y472239D01*
X671546Y471989D01*
X671296Y471739D01*
X671005Y471572D01*
X670713Y471489D01*
X670421D01*
X670130Y471572D01*
X669880Y471697D01*
X669671Y471864D01*
G01X668405Y472531D02*
X668113Y472822D01*
X667863Y472989D01*
X667530Y473072D01*
X667238Y472989D01*
X667030Y472822D01*
X666863Y472572D01*
X666821Y472281D01*
X666863Y472031D01*
X667030Y471781D01*
X667280Y471572D01*
X667571Y471489D01*
X667905Y471572D01*
X668196Y471822D01*
X668363Y472197D01*
X668405Y472614D01*
X668321Y473156D01*
X668196Y473447D01*
X667988Y473739D01*
X667696Y473947D01*
X667405Y473989D01*
X667113Y473906D01*
X666905Y473697D01*
G01X664513Y471489D02*
Y473989D01*
X665013Y473489D01*
G01Y471489D02*
X664013D01*
G01X662121Y471781D02*
X661830Y471572D01*
X661496Y471489D01*
X661163Y471572D01*
X660871Y471822D01*
X660663Y472197D01*
X660580Y472572D01*
Y473031D01*
X660663Y473406D01*
X660871Y473739D01*
X661121Y473906D01*
X661413Y473989D01*
X661746Y473906D01*
X661996Y473739D01*
X662163Y473489D01*
X662246Y473156D01*
X662163Y472864D01*
X661955Y472572D01*
X661705Y472406D01*
X661413Y472364D01*
X661080Y472447D01*
X660830Y472656D01*
X660580Y473031D01*
G01X669796Y477781D02*
X670046Y477906D01*
X670338Y477989D01*
X670671D01*
X671046Y477864D01*
X671338Y477656D01*
X671546Y477406D01*
X671713Y476989D01*
X671755Y476614D01*
X671671Y476239D01*
X671546Y475989D01*
X671296Y475739D01*
X671005Y475572D01*
X670713Y475489D01*
X670421D01*
X670130Y475572D01*
X669880Y475697D01*
X669671Y475864D01*
G01X668405Y476531D02*
X668113Y476822D01*
X667863Y476989D01*
X667530Y477072D01*
X667238Y476989D01*
X667030Y476822D01*
X666863Y476572D01*
X666821Y476281D01*
X666863Y476031D01*
X667030Y475781D01*
X667280Y475572D01*
X667571Y475489D01*
X667905Y475572D01*
X668196Y475822D01*
X668363Y476197D01*
X668405Y476614D01*
X668321Y477156D01*
X668196Y477447D01*
X667988Y477739D01*
X667696Y477947D01*
X667405Y477989D01*
X667113Y477906D01*
X666905Y477697D01*
G01X665305Y477572D02*
X665055Y477822D01*
X664763Y477947D01*
X664430Y477989D01*
X664013Y477906D01*
X663721Y477697D01*
X663638Y477447D01*
X663680Y477197D01*
X663846Y476989D01*
X664680Y476572D01*
X665055Y476281D01*
X665305Y475864D01*
X665388Y475489D01*
X663638D01*
G01X661413Y477989D02*
X661746Y477906D01*
X661996Y477697D01*
X662163Y477447D01*
X662288Y477114D01*
X662330Y476739D01*
X662288Y476364D01*
X662163Y476031D01*
X661996Y475781D01*
X661746Y475572D01*
X661413Y475489D01*
X661080Y475572D01*
X660830Y475781D01*
X660663Y476031D01*
X660538Y476364D01*
X660496Y476739D01*
X660538Y477114D01*
X660663Y477447D01*
X660830Y477697D01*
X661080Y477906D01*
X661413Y477989D01*
G01X686792Y454767D02*
X686917Y454517D01*
X687000Y454225D01*
Y453892D01*
X686875Y453517D01*
X686667Y453225D01*
X686417Y453017D01*
X686000Y452850D01*
X685625Y452808D01*
X685250Y452892D01*
X685000Y453017D01*
X684750Y453267D01*
X684583Y453558D01*
X684500Y453850D01*
Y454142D01*
X684583Y454433D01*
X684708Y454683D01*
X684875Y454892D01*
G01X685542Y456158D02*
X685833Y456450D01*
X686000Y456700D01*
X686083Y457033D01*
X686000Y457325D01*
X685833Y457533D01*
X685583Y457700D01*
X685292Y457742D01*
X685042Y457700D01*
X684792Y457533D01*
X684583Y457283D01*
X684500Y456992D01*
X684583Y456658D01*
X684833Y456367D01*
X685208Y456200D01*
X685625Y456158D01*
X686167Y456242D01*
X686458Y456367D01*
X686750Y456575D01*
X686958Y456867D01*
X687000Y457158D01*
X686917Y457450D01*
X686708Y457658D01*
G01X685000Y459133D02*
X684708Y459383D01*
X684542Y459717D01*
X684500Y460092D01*
X684542Y460425D01*
X684750Y460758D01*
X685000Y460967D01*
X685250Y461008D01*
X685542Y460925D01*
X685750Y460633D01*
X685833Y460342D01*
Y459967D01*
G01Y460342D02*
X685958Y460592D01*
X686167Y460800D01*
X686417Y460883D01*
X686667Y460800D01*
X686875Y460592D01*
X687000Y460217D01*
X686958Y459842D01*
X686792Y459467D01*
G01X685000Y462233D02*
X684708Y462483D01*
X684542Y462817D01*
X684500Y463192D01*
X684542Y463525D01*
X684750Y463858D01*
X685000Y464067D01*
X685250Y464108D01*
X685542Y464025D01*
X685750Y463733D01*
X685833Y463442D01*
Y463067D01*
G01Y463442D02*
X685958Y463692D01*
X686167Y463900D01*
X686417Y463983D01*
X686667Y463900D01*
X686875Y463692D01*
X687000Y463317D01*
X686958Y462942D01*
X686792Y462567D01*
G01X690233Y443992D02*
X690483Y444117D01*
X690775Y444200D01*
X691108D01*
X691483Y444075D01*
X691775Y443867D01*
X691983Y443617D01*
X692150Y443200D01*
X692192Y442825D01*
X692108Y442450D01*
X691983Y442200D01*
X691733Y441950D01*
X691442Y441783D01*
X691150Y441700D01*
X690858D01*
X690567Y441783D01*
X690317Y441908D01*
X690108Y442075D01*
G01X688842Y442742D02*
X688550Y443033D01*
X688300Y443200D01*
X687967Y443283D01*
X687675Y443200D01*
X687467Y443033D01*
X687300Y442783D01*
X687258Y442492D01*
X687300Y442242D01*
X687467Y441992D01*
X687717Y441783D01*
X688008Y441700D01*
X688342Y441783D01*
X688633Y442033D01*
X688800Y442408D01*
X688842Y442825D01*
X688758Y443367D01*
X688633Y443658D01*
X688425Y443950D01*
X688133Y444158D01*
X687842Y444200D01*
X687550Y444117D01*
X687342Y443908D01*
G01X685867Y442200D02*
X685617Y441908D01*
X685283Y441742D01*
X684908Y441700D01*
X684575Y441742D01*
X684242Y441950D01*
X684033Y442200D01*
X683992Y442450D01*
X684075Y442742D01*
X684367Y442950D01*
X684658Y443033D01*
X685033D01*
G01X684658D02*
X684408Y443158D01*
X684200Y443367D01*
X684117Y443617D01*
X684200Y443867D01*
X684408Y444075D01*
X684783Y444200D01*
X685158Y444158D01*
X685533Y443992D01*
G01X681350Y441700D02*
Y444200D01*
X682892Y442408D01*
X680808D01*
G01X669796Y465781D02*
X670046Y465906D01*
X670338Y465989D01*
X670671D01*
X671046Y465864D01*
X671338Y465656D01*
X671546Y465406D01*
X671713Y464989D01*
X671755Y464614D01*
X671671Y464239D01*
X671546Y463989D01*
X671296Y463739D01*
X671005Y463572D01*
X670713Y463489D01*
X670421D01*
X670130Y463572D01*
X669880Y463697D01*
X669671Y463864D01*
G01X668405Y464531D02*
X668113Y464822D01*
X667863Y464989D01*
X667530Y465072D01*
X667238Y464989D01*
X667030Y464822D01*
X666863Y464572D01*
X666821Y464281D01*
X666863Y464031D01*
X667030Y463781D01*
X667280Y463572D01*
X667571Y463489D01*
X667905Y463572D01*
X668196Y463822D01*
X668363Y464197D01*
X668405Y464614D01*
X668321Y465156D01*
X668196Y465447D01*
X667988Y465739D01*
X667696Y465947D01*
X667405Y465989D01*
X667113Y465906D01*
X666905Y465697D01*
G01X664013Y463489D02*
Y465989D01*
X665555Y464197D01*
X663471D01*
G01X661413Y463489D02*
Y465989D01*
X661913Y465489D01*
G01Y463489D02*
X660913D01*
G01X677549Y456867D02*
X677674Y456617D01*
X677757Y456325D01*
Y455992D01*
X677632Y455617D01*
X677424Y455325D01*
X677174Y455117D01*
X676757Y454950D01*
X676382Y454908D01*
X676007Y454992D01*
X675757Y455117D01*
X675507Y455367D01*
X675340Y455658D01*
X675257Y455950D01*
Y456242D01*
X675340Y456533D01*
X675465Y456783D01*
X675632Y456992D01*
G01X676299Y458258D02*
X676590Y458550D01*
X676757Y458800D01*
X676840Y459133D01*
X676757Y459425D01*
X676590Y459633D01*
X676340Y459800D01*
X676049Y459842D01*
X675799Y459800D01*
X675549Y459633D01*
X675340Y459383D01*
X675257Y459092D01*
X675340Y458758D01*
X675590Y458467D01*
X675965Y458300D01*
X676382Y458258D01*
X676924Y458342D01*
X677215Y458467D01*
X677507Y458675D01*
X677715Y458967D01*
X677757Y459258D01*
X677674Y459550D01*
X677465Y459758D01*
G01X675257Y462150D02*
X677757D01*
X677257Y461650D01*
G01X675257D02*
Y462650D01*
G01Y465167D02*
X675799Y465250D01*
X676257Y465375D01*
X676674Y465542D01*
X677132Y465750D01*
X677757Y466083D01*
Y464417D01*
G01X720436Y482716D02*
Y485216D01*
X719395D01*
X719061Y485091D01*
X718853Y484924D01*
X718770Y484591D01*
X718853Y484258D01*
X719103Y484049D01*
X719395Y483924D01*
X720436D01*
G01X719395D02*
X718770Y482716D01*
G01X716503D02*
X716211Y482758D01*
X715878Y482883D01*
X715670Y483091D01*
X715586Y483383D01*
X715670Y483674D01*
X715920Y483924D01*
X716295Y484049D01*
X716711D01*
X716961Y484133D01*
X717170Y484341D01*
X717253Y484633D01*
X717128Y484924D01*
X716836Y485133D01*
X716503Y485216D01*
X716170Y485133D01*
X715878Y484924D01*
X715753Y484633D01*
X715836Y484341D01*
X716045Y484133D01*
X716295Y484049D01*
X716711D01*
X717086Y483924D01*
X717336Y483674D01*
X717420Y483383D01*
X717336Y483091D01*
X717128Y482883D01*
X716795Y482758D01*
X716503Y482716D01*
G01X713403D02*
Y485216D01*
X713903Y484716D01*
G01Y482716D02*
X712903D01*
G01X711095Y483758D02*
X710803Y484049D01*
X710553Y484216D01*
X710220Y484299D01*
X709928Y484216D01*
X709720Y484049D01*
X709553Y483799D01*
X709511Y483508D01*
X709553Y483258D01*
X709720Y483008D01*
X709970Y482799D01*
X710261Y482716D01*
X710595Y482799D01*
X710886Y483049D01*
X711053Y483424D01*
X711095Y483841D01*
X711011Y484383D01*
X710886Y484674D01*
X710678Y484966D01*
X710386Y485174D01*
X710095Y485216D01*
X709803Y485133D01*
X709595Y484924D01*
G01X706291Y486208D02*
Y482208D01*
X698891D01*
G01X720436Y478716D02*
Y481216D01*
X719395D01*
X719061Y481091D01*
X718853Y480924D01*
X718770Y480591D01*
X718853Y480258D01*
X719103Y480049D01*
X719395Y479924D01*
X720436D01*
G01X719395D02*
X718770Y478716D01*
G01X716503D02*
X716211Y478758D01*
X715878Y478883D01*
X715670Y479091D01*
X715586Y479383D01*
X715670Y479674D01*
X715920Y479924D01*
X716295Y480049D01*
X716711D01*
X716961Y480133D01*
X717170Y480341D01*
X717253Y480633D01*
X717128Y480924D01*
X716836Y481133D01*
X716503Y481216D01*
X716170Y481133D01*
X715878Y480924D01*
X715753Y480633D01*
X715836Y480341D01*
X716045Y480133D01*
X716295Y480049D01*
X716711D01*
X717086Y479924D01*
X717336Y479674D01*
X717420Y479383D01*
X717336Y479091D01*
X717128Y478883D01*
X716795Y478758D01*
X716503Y478716D01*
G01X713403D02*
Y481216D01*
X713903Y480716D01*
G01Y478716D02*
X712903D01*
G01X711220Y479091D02*
X710970Y478883D01*
X710678Y478758D01*
X710303Y478716D01*
X709928Y478799D01*
X709636Y478966D01*
X709428Y479258D01*
X709386Y479591D01*
X709470Y479924D01*
X709678Y480133D01*
X709970Y480299D01*
X710261Y480341D01*
X710553Y480299D01*
X710928Y480133D01*
X710803Y481216D01*
X709678D01*
G01X694344Y478189D02*
Y482189D01*
X701744D01*
G01X691983Y448500D02*
Y451000D01*
X690942D01*
X690608Y450875D01*
X690400Y450708D01*
X690317Y450375D01*
X690400Y450042D01*
X690650Y449833D01*
X690942Y449708D01*
X691983D01*
G01X690942D02*
X690317Y448500D01*
G01X688050D02*
X687758Y448542D01*
X687425Y448667D01*
X687217Y448875D01*
X687133Y449167D01*
X687217Y449458D01*
X687467Y449708D01*
X687842Y449833D01*
X688258D01*
X688508Y449917D01*
X688717Y450125D01*
X688800Y450417D01*
X688675Y450708D01*
X688383Y450917D01*
X688050Y451000D01*
X687717Y450917D01*
X687425Y450708D01*
X687300Y450417D01*
X687383Y450125D01*
X687592Y449917D01*
X687842Y449833D01*
X688258D01*
X688633Y449708D01*
X688883Y449458D01*
X688967Y449167D01*
X688883Y448875D01*
X688675Y448667D01*
X688342Y448542D01*
X688050Y448500D01*
G01X685867Y449000D02*
X685617Y448708D01*
X685283Y448542D01*
X684908Y448500D01*
X684575Y448542D01*
X684242Y448750D01*
X684033Y449000D01*
X683992Y449250D01*
X684075Y449542D01*
X684367Y449750D01*
X684658Y449833D01*
X685033D01*
G01X684658D02*
X684408Y449958D01*
X684200Y450167D01*
X684117Y450417D01*
X684200Y450667D01*
X684408Y450875D01*
X684783Y451000D01*
X685158Y450958D01*
X685533Y450792D01*
G01X681350Y448500D02*
Y451000D01*
X682892Y449208D01*
X680808D01*
G01X698800Y457000D02*
Y453000D01*
X691400D01*
G01X691983Y437700D02*
Y440200D01*
X690942D01*
X690608Y440075D01*
X690400Y439908D01*
X690317Y439575D01*
X690400Y439242D01*
X690650Y439033D01*
X690942Y438908D01*
X691983D01*
G01X690942D02*
X690317Y437700D01*
G01X688967Y438075D02*
X688717Y437867D01*
X688425Y437742D01*
X688050Y437700D01*
X687675Y437783D01*
X687383Y437950D01*
X687175Y438242D01*
X687133Y438575D01*
X687217Y438908D01*
X687425Y439117D01*
X687717Y439283D01*
X688008Y439325D01*
X688300Y439283D01*
X688675Y439117D01*
X688550Y440200D01*
X687425D01*
G01X685742Y439783D02*
X685492Y440033D01*
X685200Y440158D01*
X684867Y440200D01*
X684450Y440117D01*
X684158Y439908D01*
X684075Y439658D01*
X684117Y439408D01*
X684283Y439200D01*
X685117Y438783D01*
X685492Y438492D01*
X685742Y438075D01*
X685825Y437700D01*
X684075D01*
G01X681933D02*
X681850Y438242D01*
X681725Y438700D01*
X681558Y439117D01*
X681350Y439575D01*
X681017Y440200D01*
X682683D01*
G01X703700Y444100D02*
Y440100D01*
X696300D01*
G01X710000Y463483D02*
X708208D01*
X707833Y463650D01*
X707583Y463983D01*
X707500Y464400D01*
X707583Y464817D01*
X707833Y465150D01*
X708208Y465317D01*
X710000D01*
G01X707500Y467500D02*
X707542Y467792D01*
X707667Y468125D01*
X707875Y468333D01*
X708167Y468417D01*
X708458Y468333D01*
X708708Y468083D01*
X708833Y467708D01*
Y467292D01*
X708917Y467042D01*
X709125Y466833D01*
X709417Y466750D01*
X709708Y466875D01*
X709917Y467167D01*
X710000Y467500D01*
X709917Y467833D01*
X709708Y468125D01*
X709417Y468250D01*
X709125Y468167D01*
X708917Y467958D01*
X708833Y467708D01*
Y467292D01*
X708708Y466917D01*
X708458Y466667D01*
X708167Y466583D01*
X707875Y466667D01*
X707667Y466875D01*
X707542Y467208D01*
X707500Y467500D01*
G01X708000Y469683D02*
X707708Y469933D01*
X707542Y470267D01*
X707500Y470642D01*
X707542Y470975D01*
X707750Y471308D01*
X708000Y471517D01*
X708250Y471558D01*
X708542Y471475D01*
X708750Y471183D01*
X708833Y470892D01*
Y470517D01*
G01Y470892D02*
X708958Y471142D01*
X709167Y471350D01*
X709417Y471433D01*
X709667Y471350D01*
X709875Y471142D01*
X710000Y470767D01*
X709958Y470392D01*
X709792Y470017D01*
G01X703250Y469586D02*
X693050D01*
G01X703250Y464986D02*
Y469586D01*
G01X692350Y464986D02*
X703250D01*
G01X692350D02*
Y476286D01*
G01X693550Y467286D02*
X692350Y466086D01*
G01X693550Y467286D02*
X692350Y468486D01*
G01X687964Y528138D02*
X688089Y527888D01*
X688172Y527596D01*
Y527263D01*
X688047Y526888D01*
X687839Y526596D01*
X687589Y526388D01*
X687172Y526221D01*
X686797Y526179D01*
X686422Y526263D01*
X686172Y526388D01*
X685922Y526638D01*
X685755Y526929D01*
X685672Y527221D01*
Y527513D01*
X685755Y527804D01*
X685880Y528054D01*
X686047Y528263D01*
G01X686714Y529529D02*
X687005Y529821D01*
X687172Y530071D01*
X687255Y530404D01*
X687172Y530696D01*
X687005Y530904D01*
X686755Y531071D01*
X686464Y531113D01*
X686214Y531071D01*
X685964Y530904D01*
X685755Y530654D01*
X685672Y530363D01*
X685755Y530029D01*
X686005Y529738D01*
X686380Y529571D01*
X686797Y529529D01*
X687339Y529613D01*
X687630Y529738D01*
X687922Y529946D01*
X688130Y530238D01*
X688172Y530529D01*
X688089Y530821D01*
X687880Y531029D01*
G01X685672Y533421D02*
X688172D01*
X687672Y532921D01*
G01X685672D02*
Y533921D01*
G01X686047Y535604D02*
X685839Y535854D01*
X685714Y536146D01*
X685672Y536521D01*
X685755Y536896D01*
X685922Y537188D01*
X686214Y537396D01*
X686547Y537438D01*
X686880Y537354D01*
X687089Y537146D01*
X687255Y536854D01*
X687297Y536563D01*
X687255Y536271D01*
X687089Y535896D01*
X688172Y536021D01*
Y537146D01*
G01X691964Y528138D02*
X692089Y527888D01*
X692172Y527596D01*
Y527263D01*
X692047Y526888D01*
X691839Y526596D01*
X691589Y526388D01*
X691172Y526221D01*
X690797Y526179D01*
X690422Y526263D01*
X690172Y526388D01*
X689922Y526638D01*
X689755Y526929D01*
X689672Y527221D01*
Y527513D01*
X689755Y527804D01*
X689880Y528054D01*
X690047Y528263D01*
G01X690714Y529529D02*
X691005Y529821D01*
X691172Y530071D01*
X691255Y530404D01*
X691172Y530696D01*
X691005Y530904D01*
X690755Y531071D01*
X690464Y531113D01*
X690214Y531071D01*
X689964Y530904D01*
X689755Y530654D01*
X689672Y530363D01*
X689755Y530029D01*
X690005Y529738D01*
X690380Y529571D01*
X690797Y529529D01*
X691339Y529613D01*
X691630Y529738D01*
X691922Y529946D01*
X692130Y530238D01*
X692172Y530529D01*
X692089Y530821D01*
X691880Y531029D01*
G01X689672Y533421D02*
X692172D01*
X691672Y532921D01*
G01X689672D02*
Y533921D01*
G01X690714Y535729D02*
X691005Y536021D01*
X691172Y536271D01*
X691255Y536604D01*
X691172Y536896D01*
X691005Y537104D01*
X690755Y537271D01*
X690464Y537313D01*
X690214Y537271D01*
X689964Y537104D01*
X689755Y536854D01*
X689672Y536563D01*
X689755Y536229D01*
X690005Y535938D01*
X690380Y535771D01*
X690797Y535729D01*
X691339Y535813D01*
X691630Y535938D01*
X691922Y536146D01*
X692130Y536438D01*
X692172Y536729D01*
X692089Y537021D01*
X691880Y537229D01*
G01X706552Y501425D02*
X706802Y501550D01*
X707094Y501633D01*
X707427D01*
X707802Y501508D01*
X708094Y501300D01*
X708302Y501050D01*
X708469Y500633D01*
X708511Y500258D01*
X708427Y499883D01*
X708302Y499633D01*
X708052Y499383D01*
X707761Y499216D01*
X707469Y499133D01*
X707177D01*
X706886Y499216D01*
X706636Y499341D01*
X706427Y499508D01*
G01X705161Y500175D02*
X704869Y500466D01*
X704619Y500633D01*
X704286Y500716D01*
X703994Y500633D01*
X703786Y500466D01*
X703619Y500216D01*
X703577Y499925D01*
X703619Y499675D01*
X703786Y499425D01*
X704036Y499216D01*
X704327Y499133D01*
X704661Y499216D01*
X704952Y499466D01*
X705119Y499841D01*
X705161Y500258D01*
X705077Y500800D01*
X704952Y501091D01*
X704744Y501383D01*
X704452Y501591D01*
X704161Y501633D01*
X703869Y501550D01*
X703661Y501341D01*
G01X702061Y501216D02*
X701811Y501466D01*
X701519Y501591D01*
X701186Y501633D01*
X700769Y501550D01*
X700477Y501341D01*
X700394Y501091D01*
X700436Y500841D01*
X700602Y500633D01*
X701436Y500216D01*
X701811Y499925D01*
X702061Y499508D01*
X702144Y499133D01*
X700394D01*
G01X699086Y499633D02*
X698836Y499341D01*
X698502Y499175D01*
X698127Y499133D01*
X697794Y499175D01*
X697461Y499383D01*
X697252Y499633D01*
X697211Y499883D01*
X697294Y500175D01*
X697586Y500383D01*
X697877Y500466D01*
X698252D01*
G01X697877D02*
X697627Y500591D01*
X697419Y500800D01*
X697336Y501050D01*
X697419Y501300D01*
X697627Y501508D01*
X698002Y501633D01*
X698377Y501591D01*
X698752Y501425D01*
G01X706552Y505425D02*
X706802Y505550D01*
X707094Y505633D01*
X707427D01*
X707802Y505508D01*
X708094Y505300D01*
X708302Y505050D01*
X708469Y504633D01*
X708511Y504258D01*
X708427Y503883D01*
X708302Y503633D01*
X708052Y503383D01*
X707761Y503216D01*
X707469Y503133D01*
X707177D01*
X706886Y503216D01*
X706636Y503341D01*
X706427Y503508D01*
G01X705161Y504175D02*
X704869Y504466D01*
X704619Y504633D01*
X704286Y504716D01*
X703994Y504633D01*
X703786Y504466D01*
X703619Y504216D01*
X703577Y503925D01*
X703619Y503675D01*
X703786Y503425D01*
X704036Y503216D01*
X704327Y503133D01*
X704661Y503216D01*
X704952Y503466D01*
X705119Y503841D01*
X705161Y504258D01*
X705077Y504800D01*
X704952Y505091D01*
X704744Y505383D01*
X704452Y505591D01*
X704161Y505633D01*
X703869Y505550D01*
X703661Y505341D01*
G01X702061Y505216D02*
X701811Y505466D01*
X701519Y505591D01*
X701186Y505633D01*
X700769Y505550D01*
X700477Y505341D01*
X700394Y505091D01*
X700436Y504841D01*
X700602Y504633D01*
X701436Y504216D01*
X701811Y503925D01*
X702061Y503508D01*
X702144Y503133D01*
X700394D01*
G01X697669D02*
Y505633D01*
X699211Y503841D01*
X697127D01*
G01X695964Y528138D02*
X696089Y527888D01*
X696172Y527596D01*
Y527263D01*
X696047Y526888D01*
X695839Y526596D01*
X695589Y526388D01*
X695172Y526221D01*
X694797Y526179D01*
X694422Y526263D01*
X694172Y526388D01*
X693922Y526638D01*
X693755Y526929D01*
X693672Y527221D01*
Y527513D01*
X693755Y527804D01*
X693880Y528054D01*
X694047Y528263D01*
G01X694714Y529529D02*
X695005Y529821D01*
X695172Y530071D01*
X695255Y530404D01*
X695172Y530696D01*
X695005Y530904D01*
X694755Y531071D01*
X694464Y531113D01*
X694214Y531071D01*
X693964Y530904D01*
X693755Y530654D01*
X693672Y530363D01*
X693755Y530029D01*
X694005Y529738D01*
X694380Y529571D01*
X694797Y529529D01*
X695339Y529613D01*
X695630Y529738D01*
X695922Y529946D01*
X696130Y530238D01*
X696172Y530529D01*
X696089Y530821D01*
X695880Y531029D01*
G01X694172Y532504D02*
X693880Y532754D01*
X693714Y533088D01*
X693672Y533463D01*
X693714Y533796D01*
X693922Y534129D01*
X694172Y534338D01*
X694422Y534379D01*
X694714Y534296D01*
X694922Y534004D01*
X695005Y533713D01*
Y533338D01*
G01Y533713D02*
X695130Y533963D01*
X695339Y534171D01*
X695589Y534254D01*
X695839Y534171D01*
X696047Y533963D01*
X696172Y533588D01*
X696130Y533213D01*
X695964Y532838D01*
G01X696172Y536521D02*
X696089Y536188D01*
X695880Y535938D01*
X695630Y535771D01*
X695297Y535646D01*
X694922Y535604D01*
X694547Y535646D01*
X694214Y535771D01*
X693964Y535938D01*
X693755Y536188D01*
X693672Y536521D01*
X693755Y536854D01*
X693964Y537104D01*
X694214Y537271D01*
X694547Y537396D01*
X694922Y537438D01*
X695297Y537396D01*
X695630Y537271D01*
X695880Y537104D01*
X696089Y536854D01*
X696172Y536521D01*
G01X706552Y497425D02*
X706802Y497550D01*
X707094Y497633D01*
X707427D01*
X707802Y497508D01*
X708094Y497300D01*
X708302Y497050D01*
X708469Y496633D01*
X708511Y496258D01*
X708427Y495883D01*
X708302Y495633D01*
X708052Y495383D01*
X707761Y495216D01*
X707469Y495133D01*
X707177D01*
X706886Y495216D01*
X706636Y495341D01*
X706427Y495508D01*
G01X705161Y496175D02*
X704869Y496466D01*
X704619Y496633D01*
X704286Y496716D01*
X703994Y496633D01*
X703786Y496466D01*
X703619Y496216D01*
X703577Y495925D01*
X703619Y495675D01*
X703786Y495425D01*
X704036Y495216D01*
X704327Y495133D01*
X704661Y495216D01*
X704952Y495466D01*
X705119Y495841D01*
X705161Y496258D01*
X705077Y496800D01*
X704952Y497091D01*
X704744Y497383D01*
X704452Y497591D01*
X704161Y497633D01*
X703869Y497550D01*
X703661Y497341D01*
G01X702061Y497216D02*
X701811Y497466D01*
X701519Y497591D01*
X701186Y497633D01*
X700769Y497550D01*
X700477Y497341D01*
X700394Y497091D01*
X700436Y496841D01*
X700602Y496633D01*
X701436Y496216D01*
X701811Y495925D01*
X702061Y495508D01*
X702144Y495133D01*
X700394D01*
G01X698169D02*
Y497633D01*
X698669Y497133D01*
G01Y495133D02*
X697669D01*
G01X699964Y528138D02*
X700089Y527888D01*
X700172Y527596D01*
Y527263D01*
X700047Y526888D01*
X699839Y526596D01*
X699589Y526388D01*
X699172Y526221D01*
X698797Y526179D01*
X698422Y526263D01*
X698172Y526388D01*
X697922Y526638D01*
X697755Y526929D01*
X697672Y527221D01*
Y527513D01*
X697755Y527804D01*
X697880Y528054D01*
X698047Y528263D01*
G01X698714Y529529D02*
X699005Y529821D01*
X699172Y530071D01*
X699255Y530404D01*
X699172Y530696D01*
X699005Y530904D01*
X698755Y531071D01*
X698464Y531113D01*
X698214Y531071D01*
X697964Y530904D01*
X697755Y530654D01*
X697672Y530363D01*
X697755Y530029D01*
X698005Y529738D01*
X698380Y529571D01*
X698797Y529529D01*
X699339Y529613D01*
X699630Y529738D01*
X699922Y529946D01*
X700130Y530238D01*
X700172Y530529D01*
X700089Y530821D01*
X699880Y531029D01*
G01X697672Y533421D02*
X700172D01*
X699672Y532921D01*
G01X697672D02*
Y533921D01*
G01Y537021D02*
X700172D01*
X698380Y535479D01*
Y537563D01*
G01X748099Y544560D02*
X748224Y544310D01*
X748307Y544018D01*
Y543685D01*
X748182Y543310D01*
X747974Y543018D01*
X747724Y542810D01*
X747307Y542643D01*
X746932Y542601D01*
X746557Y542685D01*
X746307Y542810D01*
X746057Y543060D01*
X745890Y543351D01*
X745807Y543643D01*
Y543935D01*
X745890Y544226D01*
X746015Y544476D01*
X746182Y544685D01*
G01X746849Y545951D02*
X747140Y546243D01*
X747307Y546493D01*
X747390Y546826D01*
X747307Y547118D01*
X747140Y547326D01*
X746890Y547493D01*
X746599Y547535D01*
X746349Y547493D01*
X746099Y547326D01*
X745890Y547076D01*
X745807Y546785D01*
X745890Y546451D01*
X746140Y546160D01*
X746515Y545993D01*
X746932Y545951D01*
X747474Y546035D01*
X747765Y546160D01*
X748057Y546368D01*
X748265Y546660D01*
X748307Y546951D01*
X748224Y547243D01*
X748015Y547451D01*
G01X748307Y549843D02*
X748224Y549510D01*
X748015Y549260D01*
X747765Y549093D01*
X747432Y548968D01*
X747057Y548926D01*
X746682Y548968D01*
X746349Y549093D01*
X746099Y549260D01*
X745890Y549510D01*
X745807Y549843D01*
X745890Y550176D01*
X746099Y550426D01*
X746349Y550593D01*
X746682Y550718D01*
X747057Y550760D01*
X747432Y550718D01*
X747765Y550593D01*
X748015Y550426D01*
X748224Y550176D01*
X748307Y549843D01*
G01X746182Y552026D02*
X745974Y552276D01*
X745849Y552568D01*
X745807Y552943D01*
X745890Y553318D01*
X746057Y553610D01*
X746349Y553818D01*
X746682Y553860D01*
X747015Y553776D01*
X747224Y553568D01*
X747390Y553276D01*
X747432Y552985D01*
X747390Y552693D01*
X747224Y552318D01*
X748307Y552443D01*
Y553568D01*
G01X786105Y523325D02*
X786230Y523075D01*
X786313Y522783D01*
Y522450D01*
X786188Y522075D01*
X785980Y521783D01*
X785730Y521575D01*
X785313Y521408D01*
X784938Y521366D01*
X784563Y521450D01*
X784313Y521575D01*
X784063Y521825D01*
X783896Y522116D01*
X783813Y522408D01*
Y522700D01*
X783896Y522991D01*
X784021Y523241D01*
X784188Y523450D01*
G01X784855Y524716D02*
X785146Y525008D01*
X785313Y525258D01*
X785396Y525591D01*
X785313Y525883D01*
X785146Y526091D01*
X784896Y526258D01*
X784605Y526300D01*
X784355Y526258D01*
X784105Y526091D01*
X783896Y525841D01*
X783813Y525550D01*
X783896Y525216D01*
X784146Y524925D01*
X784521Y524758D01*
X784938Y524716D01*
X785480Y524800D01*
X785771Y524925D01*
X786063Y525133D01*
X786271Y525425D01*
X786313Y525716D01*
X786230Y526008D01*
X786021Y526216D01*
G01X786313Y528608D02*
X786230Y528275D01*
X786021Y528025D01*
X785771Y527858D01*
X785438Y527733D01*
X785063Y527691D01*
X784688Y527733D01*
X784355Y527858D01*
X784105Y528025D01*
X783896Y528275D01*
X783813Y528608D01*
X783896Y528941D01*
X784105Y529191D01*
X784355Y529358D01*
X784688Y529483D01*
X785063Y529525D01*
X785438Y529483D01*
X785771Y529358D01*
X786021Y529191D01*
X786230Y528941D01*
X786313Y528608D01*
G01X784105Y531000D02*
X783896Y531291D01*
X783813Y531625D01*
X783896Y531958D01*
X784146Y532250D01*
X784521Y532458D01*
X784896Y532541D01*
X785355D01*
X785730Y532458D01*
X786063Y532250D01*
X786230Y532000D01*
X786313Y531708D01*
X786230Y531375D01*
X786063Y531125D01*
X785813Y530958D01*
X785480Y530875D01*
X785188Y530958D01*
X784896Y531166D01*
X784730Y531416D01*
X784688Y531708D01*
X784771Y532041D01*
X784980Y532291D01*
X785355Y532541D01*
G01X743669Y544714D02*
X743794Y544464D01*
X743877Y544172D01*
Y543839D01*
X743752Y543464D01*
X743544Y543172D01*
X743294Y542964D01*
X742877Y542797D01*
X742502Y542755D01*
X742127Y542839D01*
X741877Y542964D01*
X741627Y543214D01*
X741460Y543505D01*
X741377Y543797D01*
Y544089D01*
X741460Y544380D01*
X741585Y544630D01*
X741752Y544839D01*
G01X742419Y546105D02*
X742710Y546397D01*
X742877Y546647D01*
X742960Y546980D01*
X742877Y547272D01*
X742710Y547480D01*
X742460Y547647D01*
X742169Y547689D01*
X741919Y547647D01*
X741669Y547480D01*
X741460Y547230D01*
X741377Y546939D01*
X741460Y546605D01*
X741710Y546314D01*
X742085Y546147D01*
X742502Y546105D01*
X743044Y546189D01*
X743335Y546314D01*
X743627Y546522D01*
X743835Y546814D01*
X743877Y547105D01*
X743794Y547397D01*
X743585Y547605D01*
G01X741377Y549997D02*
X743877D01*
X743377Y549497D01*
G01X741377D02*
Y550497D01*
G01X743460Y552305D02*
X743710Y552555D01*
X743835Y552847D01*
X743877Y553180D01*
X743794Y553597D01*
X743585Y553889D01*
X743335Y553972D01*
X743085Y553930D01*
X742877Y553764D01*
X742460Y552930D01*
X742169Y552555D01*
X741752Y552305D01*
X741377Y552222D01*
Y553972D01*
G01X739169Y544614D02*
X739294Y544364D01*
X739377Y544072D01*
Y543739D01*
X739252Y543364D01*
X739044Y543072D01*
X738794Y542864D01*
X738377Y542697D01*
X738002Y542655D01*
X737627Y542739D01*
X737377Y542864D01*
X737127Y543114D01*
X736960Y543405D01*
X736877Y543697D01*
Y543989D01*
X736960Y544280D01*
X737085Y544530D01*
X737252Y544739D01*
G01X737919Y546005D02*
X738210Y546297D01*
X738377Y546547D01*
X738460Y546880D01*
X738377Y547172D01*
X738210Y547380D01*
X737960Y547547D01*
X737669Y547589D01*
X737419Y547547D01*
X737169Y547380D01*
X736960Y547130D01*
X736877Y546839D01*
X736960Y546505D01*
X737210Y546214D01*
X737585Y546047D01*
X738002Y546005D01*
X738544Y546089D01*
X738835Y546214D01*
X739127Y546422D01*
X739335Y546714D01*
X739377Y547005D01*
X739294Y547297D01*
X739085Y547505D01*
G01X736877Y549897D02*
X739377D01*
X738877Y549397D01*
G01X736877D02*
Y550397D01*
G01X737377Y552080D02*
X737085Y552330D01*
X736919Y552664D01*
X736877Y553039D01*
X736919Y553372D01*
X737127Y553705D01*
X737377Y553914D01*
X737627Y553955D01*
X737919Y553872D01*
X738127Y553580D01*
X738210Y553289D01*
Y552914D01*
G01Y553289D02*
X738335Y553539D01*
X738544Y553747D01*
X738794Y553830D01*
X739044Y553747D01*
X739252Y553539D01*
X739377Y553164D01*
X739335Y552789D01*
X739169Y552414D01*
G01X752099Y544560D02*
X752224Y544310D01*
X752307Y544018D01*
Y543685D01*
X752182Y543310D01*
X751974Y543018D01*
X751724Y542810D01*
X751307Y542643D01*
X750932Y542601D01*
X750557Y542685D01*
X750307Y542810D01*
X750057Y543060D01*
X749890Y543351D01*
X749807Y543643D01*
Y543935D01*
X749890Y544226D01*
X750015Y544476D01*
X750182Y544685D01*
G01X750849Y545951D02*
X751140Y546243D01*
X751307Y546493D01*
X751390Y546826D01*
X751307Y547118D01*
X751140Y547326D01*
X750890Y547493D01*
X750599Y547535D01*
X750349Y547493D01*
X750099Y547326D01*
X749890Y547076D01*
X749807Y546785D01*
X749890Y546451D01*
X750140Y546160D01*
X750515Y545993D01*
X750932Y545951D01*
X751474Y546035D01*
X751765Y546160D01*
X752057Y546368D01*
X752265Y546660D01*
X752307Y546951D01*
X752224Y547243D01*
X752015Y547451D01*
G01X751890Y549051D02*
X752140Y549301D01*
X752265Y549593D01*
X752307Y549926D01*
X752224Y550343D01*
X752015Y550635D01*
X751765Y550718D01*
X751515Y550676D01*
X751307Y550510D01*
X750890Y549676D01*
X750599Y549301D01*
X750182Y549051D01*
X749807Y548968D01*
Y550718D01*
G01X750849Y552151D02*
X751140Y552443D01*
X751307Y552693D01*
X751390Y553026D01*
X751307Y553318D01*
X751140Y553526D01*
X750890Y553693D01*
X750599Y553735D01*
X750349Y553693D01*
X750099Y553526D01*
X749890Y553276D01*
X749807Y552985D01*
X749890Y552651D01*
X750140Y552360D01*
X750515Y552193D01*
X750932Y552151D01*
X751474Y552235D01*
X751765Y552360D01*
X752057Y552568D01*
X752265Y552860D01*
X752307Y553151D01*
X752224Y553443D01*
X752015Y553651D01*
G01X780099Y541060D02*
X780224Y540810D01*
X780307Y540518D01*
Y540185D01*
X780182Y539810D01*
X779974Y539518D01*
X779724Y539310D01*
X779307Y539143D01*
X778932Y539101D01*
X778557Y539185D01*
X778307Y539310D01*
X778057Y539560D01*
X777890Y539851D01*
X777807Y540143D01*
Y540435D01*
X777890Y540726D01*
X778015Y540976D01*
X778182Y541185D01*
G01X778849Y542451D02*
X779140Y542743D01*
X779307Y542993D01*
X779390Y543326D01*
X779307Y543618D01*
X779140Y543826D01*
X778890Y543993D01*
X778599Y544035D01*
X778349Y543993D01*
X778099Y543826D01*
X777890Y543576D01*
X777807Y543285D01*
X777890Y542951D01*
X778140Y542660D01*
X778515Y542493D01*
X778932Y542451D01*
X779474Y542535D01*
X779765Y542660D01*
X780057Y542868D01*
X780265Y543160D01*
X780307Y543451D01*
X780224Y543743D01*
X780015Y543951D01*
G01X779890Y545551D02*
X780140Y545801D01*
X780265Y546093D01*
X780307Y546426D01*
X780224Y546843D01*
X780015Y547135D01*
X779765Y547218D01*
X779515Y547176D01*
X779307Y547010D01*
X778890Y546176D01*
X778599Y545801D01*
X778182Y545551D01*
X777807Y545468D01*
Y547218D01*
G01Y549443D02*
X777849Y549735D01*
X777974Y550068D01*
X778182Y550276D01*
X778474Y550360D01*
X778765Y550276D01*
X779015Y550026D01*
X779140Y549651D01*
Y549235D01*
X779224Y548985D01*
X779432Y548776D01*
X779724Y548693D01*
X780015Y548818D01*
X780224Y549110D01*
X780307Y549443D01*
X780224Y549776D01*
X780015Y550068D01*
X779724Y550193D01*
X779432Y550110D01*
X779224Y549901D01*
X779140Y549651D01*
Y549235D01*
X779015Y548860D01*
X778765Y548610D01*
X778474Y548526D01*
X778182Y548610D01*
X777974Y548818D01*
X777849Y549151D01*
X777807Y549443D01*
G01X735169Y544614D02*
X735294Y544364D01*
X735377Y544072D01*
Y543739D01*
X735252Y543364D01*
X735044Y543072D01*
X734794Y542864D01*
X734377Y542697D01*
X734002Y542655D01*
X733627Y542739D01*
X733377Y542864D01*
X733127Y543114D01*
X732960Y543405D01*
X732877Y543697D01*
Y543989D01*
X732960Y544280D01*
X733085Y544530D01*
X733252Y544739D01*
G01X733919Y546005D02*
X734210Y546297D01*
X734377Y546547D01*
X734460Y546880D01*
X734377Y547172D01*
X734210Y547380D01*
X733960Y547547D01*
X733669Y547589D01*
X733419Y547547D01*
X733169Y547380D01*
X732960Y547130D01*
X732877Y546839D01*
X732960Y546505D01*
X733210Y546214D01*
X733585Y546047D01*
X734002Y546005D01*
X734544Y546089D01*
X734835Y546214D01*
X735127Y546422D01*
X735335Y546714D01*
X735377Y547005D01*
X735294Y547297D01*
X735085Y547505D01*
G01X732877Y549897D02*
X735377D01*
X734877Y549397D01*
G01X732877D02*
Y550397D01*
G01X735377Y552997D02*
X735294Y552664D01*
X735085Y552414D01*
X734835Y552247D01*
X734502Y552122D01*
X734127Y552080D01*
X733752Y552122D01*
X733419Y552247D01*
X733169Y552414D01*
X732960Y552664D01*
X732877Y552997D01*
X732960Y553330D01*
X733169Y553580D01*
X733419Y553747D01*
X733752Y553872D01*
X734127Y553914D01*
X734502Y553872D01*
X734835Y553747D01*
X735085Y553580D01*
X735294Y553330D01*
X735377Y552997D01*
G01X783792Y540767D02*
X783917Y540517D01*
X784000Y540225D01*
Y539892D01*
X783875Y539517D01*
X783667Y539225D01*
X783417Y539017D01*
X783000Y538850D01*
X782625Y538808D01*
X782250Y538892D01*
X782000Y539017D01*
X781750Y539267D01*
X781583Y539558D01*
X781500Y539850D01*
Y540142D01*
X781583Y540433D01*
X781708Y540683D01*
X781875Y540892D01*
G01X782542Y542158D02*
X782833Y542450D01*
X783000Y542700D01*
X783083Y543033D01*
X783000Y543325D01*
X782833Y543533D01*
X782583Y543700D01*
X782292Y543742D01*
X782042Y543700D01*
X781792Y543533D01*
X781583Y543283D01*
X781500Y542992D01*
X781583Y542658D01*
X781833Y542367D01*
X782208Y542200D01*
X782625Y542158D01*
X783167Y542242D01*
X783458Y542367D01*
X783750Y542575D01*
X783958Y542867D01*
X784000Y543158D01*
X783917Y543450D01*
X783708Y543658D01*
G01X783583Y545258D02*
X783833Y545508D01*
X783958Y545800D01*
X784000Y546133D01*
X783917Y546550D01*
X783708Y546842D01*
X783458Y546925D01*
X783208Y546883D01*
X783000Y546717D01*
X782583Y545883D01*
X782292Y545508D01*
X781875Y545258D01*
X781500Y545175D01*
Y546925D01*
G01X781875Y548233D02*
X781667Y548483D01*
X781542Y548775D01*
X781500Y549150D01*
X781583Y549525D01*
X781750Y549817D01*
X782042Y550025D01*
X782375Y550067D01*
X782708Y549983D01*
X782917Y549775D01*
X783083Y549483D01*
X783125Y549192D01*
X783083Y548900D01*
X782917Y548525D01*
X784000Y548650D01*
Y549775D01*
G01X749579Y536718D02*
Y540718D01*
X756979D01*
G01X764794Y538231D02*
Y542231D01*
X772194D01*
G01X757305Y536797D02*
Y540797D01*
X764705D01*
G01X756845Y583208D02*
X759345D01*
Y584249D01*
X759220Y584583D01*
X759053Y584791D01*
X758720Y584874D01*
X758387Y584791D01*
X758178Y584541D01*
X758053Y584249D01*
Y583208D01*
G01Y584249D02*
X756845Y584874D01*
G01Y587141D02*
X756887Y587433D01*
X757012Y587766D01*
X757220Y587974D01*
X757512Y588058D01*
X757803Y587974D01*
X758053Y587724D01*
X758178Y587349D01*
Y586933D01*
X758262Y586683D01*
X758470Y586474D01*
X758762Y586391D01*
X759053Y586516D01*
X759262Y586808D01*
X759345Y587141D01*
X759262Y587474D01*
X759053Y587766D01*
X758762Y587891D01*
X758470Y587808D01*
X758262Y587599D01*
X758178Y587349D01*
Y586933D01*
X758053Y586558D01*
X757803Y586308D01*
X757512Y586224D01*
X757220Y586308D01*
X757012Y586516D01*
X756887Y586849D01*
X756845Y587141D01*
G01X759345Y590241D02*
X759262Y589908D01*
X759053Y589658D01*
X758803Y589491D01*
X758470Y589366D01*
X758095Y589324D01*
X757720Y589366D01*
X757387Y589491D01*
X757137Y589658D01*
X756928Y589908D01*
X756845Y590241D01*
X756928Y590574D01*
X757137Y590824D01*
X757387Y590991D01*
X757720Y591116D01*
X758095Y591158D01*
X758470Y591116D01*
X758803Y590991D01*
X759053Y590824D01*
X759262Y590574D01*
X759345Y590241D01*
G01X757345Y592424D02*
X757053Y592674D01*
X756887Y593008D01*
X756845Y593383D01*
X756887Y593716D01*
X757095Y594049D01*
X757345Y594258D01*
X757595Y594299D01*
X757887Y594216D01*
X758095Y593924D01*
X758178Y593633D01*
Y593258D01*
G01Y593633D02*
X758303Y593883D01*
X758512Y594091D01*
X758762Y594174D01*
X759012Y594091D01*
X759220Y593883D01*
X759345Y593508D01*
X759303Y593133D01*
X759137Y592758D01*
G01X764845Y583208D02*
X767345D01*
Y584249D01*
X767220Y584583D01*
X767053Y584791D01*
X766720Y584874D01*
X766387Y584791D01*
X766178Y584541D01*
X766053Y584249D01*
Y583208D01*
G01Y584249D02*
X764845Y584874D01*
G01Y587141D02*
X764887Y587433D01*
X765012Y587766D01*
X765220Y587974D01*
X765512Y588058D01*
X765803Y587974D01*
X766053Y587724D01*
X766178Y587349D01*
Y586933D01*
X766262Y586683D01*
X766470Y586474D01*
X766762Y586391D01*
X767053Y586516D01*
X767262Y586808D01*
X767345Y587141D01*
X767262Y587474D01*
X767053Y587766D01*
X766762Y587891D01*
X766470Y587808D01*
X766262Y587599D01*
X766178Y587349D01*
Y586933D01*
X766053Y586558D01*
X765803Y586308D01*
X765512Y586224D01*
X765220Y586308D01*
X765012Y586516D01*
X764887Y586849D01*
X764845Y587141D01*
G01X767345Y590241D02*
X767262Y589908D01*
X767053Y589658D01*
X766803Y589491D01*
X766470Y589366D01*
X766095Y589324D01*
X765720Y589366D01*
X765387Y589491D01*
X765137Y589658D01*
X764928Y589908D01*
X764845Y590241D01*
X764928Y590574D01*
X765137Y590824D01*
X765387Y590991D01*
X765720Y591116D01*
X766095Y591158D01*
X766470Y591116D01*
X766803Y590991D01*
X767053Y590824D01*
X767262Y590574D01*
X767345Y590241D01*
G01X765137Y592633D02*
X764928Y592924D01*
X764845Y593258D01*
X764928Y593591D01*
X765178Y593883D01*
X765553Y594091D01*
X765928Y594174D01*
X766387D01*
X766762Y594091D01*
X767095Y593883D01*
X767262Y593633D01*
X767345Y593341D01*
X767262Y593008D01*
X767095Y592758D01*
X766845Y592591D01*
X766512Y592508D01*
X766220Y592591D01*
X765928Y592799D01*
X765762Y593049D01*
X765720Y593341D01*
X765803Y593674D01*
X766012Y593924D01*
X766387Y594174D01*
G01X760845Y583208D02*
X763345D01*
Y584249D01*
X763220Y584583D01*
X763053Y584791D01*
X762720Y584874D01*
X762387Y584791D01*
X762178Y584541D01*
X762053Y584249D01*
Y583208D01*
G01Y584249D02*
X760845Y584874D01*
G01Y587141D02*
X760887Y587433D01*
X761012Y587766D01*
X761220Y587974D01*
X761512Y588058D01*
X761803Y587974D01*
X762053Y587724D01*
X762178Y587349D01*
Y586933D01*
X762262Y586683D01*
X762470Y586474D01*
X762762Y586391D01*
X763053Y586516D01*
X763262Y586808D01*
X763345Y587141D01*
X763262Y587474D01*
X763053Y587766D01*
X762762Y587891D01*
X762470Y587808D01*
X762262Y587599D01*
X762178Y587349D01*
Y586933D01*
X762053Y586558D01*
X761803Y586308D01*
X761512Y586224D01*
X761220Y586308D01*
X761012Y586516D01*
X760887Y586849D01*
X760845Y587141D01*
G01X763345Y590241D02*
X763262Y589908D01*
X763053Y589658D01*
X762803Y589491D01*
X762470Y589366D01*
X762095Y589324D01*
X761720Y589366D01*
X761387Y589491D01*
X761137Y589658D01*
X760928Y589908D01*
X760845Y590241D01*
X760928Y590574D01*
X761137Y590824D01*
X761387Y590991D01*
X761720Y591116D01*
X762095Y591158D01*
X762470Y591116D01*
X762803Y590991D01*
X763053Y590824D01*
X763262Y590574D01*
X763345Y590241D01*
G01X760845Y593341D02*
X760887Y593633D01*
X761012Y593966D01*
X761220Y594174D01*
X761512Y594258D01*
X761803Y594174D01*
X762053Y593924D01*
X762178Y593549D01*
Y593133D01*
X762262Y592883D01*
X762470Y592674D01*
X762762Y592591D01*
X763053Y592716D01*
X763262Y593008D01*
X763345Y593341D01*
X763262Y593674D01*
X763053Y593966D01*
X762762Y594091D01*
X762470Y594008D01*
X762262Y593799D01*
X762178Y593549D01*
Y593133D01*
X762053Y592758D01*
X761803Y592508D01*
X761512Y592424D01*
X761220Y592508D01*
X761012Y592716D01*
X760887Y593049D01*
X760845Y593341D01*
G01X853245Y168430D02*
X855745D01*
Y169471D01*
X855620Y169805D01*
X855453Y170013D01*
X855120Y170096D01*
X854787Y170013D01*
X854578Y169763D01*
X854453Y169471D01*
Y168430D01*
G01Y169471D02*
X853245Y170096D01*
G01Y172863D02*
X855745D01*
X853953Y171321D01*
Y173405D01*
G01X854287Y174671D02*
X854578Y174963D01*
X854745Y175213D01*
X854828Y175546D01*
X854745Y175838D01*
X854578Y176046D01*
X854328Y176213D01*
X854037Y176255D01*
X853787Y176213D01*
X853537Y176046D01*
X853328Y175796D01*
X853245Y175505D01*
X853328Y175171D01*
X853578Y174880D01*
X853953Y174713D01*
X854370Y174671D01*
X854912Y174755D01*
X855203Y174880D01*
X855495Y175088D01*
X855703Y175380D01*
X855745Y175671D01*
X855662Y175963D01*
X855453Y176171D01*
G01X854287Y177771D02*
X854578Y178063D01*
X854745Y178313D01*
X854828Y178646D01*
X854745Y178938D01*
X854578Y179146D01*
X854328Y179313D01*
X854037Y179355D01*
X853787Y179313D01*
X853537Y179146D01*
X853328Y178896D01*
X853245Y178605D01*
X853328Y178271D01*
X853578Y177980D01*
X853953Y177813D01*
X854370Y177771D01*
X854912Y177855D01*
X855203Y177980D01*
X855495Y178188D01*
X855703Y178480D01*
X855745Y178771D01*
X855662Y179063D01*
X855453Y179271D01*
G01X855547Y213562D02*
X855797Y213687D01*
X856089Y213770D01*
X856422D01*
X856797Y213645D01*
X857089Y213437D01*
X857297Y213187D01*
X857464Y212770D01*
X857506Y212395D01*
X857422Y212020D01*
X857297Y211770D01*
X857047Y211520D01*
X856756Y211353D01*
X856464Y211270D01*
X856172D01*
X855881Y211353D01*
X855631Y211478D01*
X855422Y211645D01*
G01X853364Y211270D02*
Y213770D01*
X853864Y213270D01*
G01Y211270D02*
X852864D01*
G01X851181Y211645D02*
X850931Y211437D01*
X850639Y211312D01*
X850264Y211270D01*
X849889Y211353D01*
X849597Y211520D01*
X849389Y211812D01*
X849347Y212145D01*
X849431Y212478D01*
X849639Y212687D01*
X849931Y212853D01*
X850222Y212895D01*
X850514Y212853D01*
X850889Y212687D01*
X850764Y213770D01*
X849639D01*
G01X847247Y211270D02*
X847164Y211812D01*
X847039Y212270D01*
X846872Y212687D01*
X846664Y213145D01*
X846331Y213770D01*
X847997D01*
G01X846103Y337004D02*
Y339504D01*
X845062D01*
X844728Y339379D01*
X844520Y339212D01*
X844437Y338879D01*
X844520Y338546D01*
X844770Y338337D01*
X845062Y338212D01*
X846103D01*
G01X845062D02*
X844437Y337004D01*
G01X842170D02*
X841878Y337046D01*
X841545Y337171D01*
X841337Y337379D01*
X841253Y337671D01*
X841337Y337962D01*
X841587Y338212D01*
X841962Y338337D01*
X842378D01*
X842628Y338421D01*
X842837Y338629D01*
X842920Y338921D01*
X842795Y339212D01*
X842503Y339421D01*
X842170Y339504D01*
X841837Y339421D01*
X841545Y339212D01*
X841420Y338921D01*
X841503Y338629D01*
X841712Y338421D01*
X841962Y338337D01*
X842378D01*
X842753Y338212D01*
X843003Y337962D01*
X843087Y337671D01*
X843003Y337379D01*
X842795Y337171D01*
X842462Y337046D01*
X842170Y337004D01*
G01X839070Y339504D02*
X839403Y339421D01*
X839653Y339212D01*
X839820Y338962D01*
X839945Y338629D01*
X839987Y338254D01*
X839945Y337879D01*
X839820Y337546D01*
X839653Y337296D01*
X839403Y337087D01*
X839070Y337004D01*
X838737Y337087D01*
X838487Y337296D01*
X838320Y337546D01*
X838195Y337879D01*
X838153Y338254D01*
X838195Y338629D01*
X838320Y338962D01*
X838487Y339212D01*
X838737Y339421D01*
X839070Y339504D01*
G01X835970Y337004D02*
Y339504D01*
X836470Y339004D01*
G01Y337004D02*
X835470D01*
G01X826039Y338820D02*
Y342820D01*
X833439D01*
G01X817016Y343114D02*
X813016D01*
Y350514D01*
G01X842566Y341604D02*
X845066D01*
Y342645D01*
X844941Y342979D01*
X844774Y343187D01*
X844441Y343270D01*
X844108Y343187D01*
X843899Y342937D01*
X843774Y342645D01*
Y341604D01*
G01Y342645D02*
X842566Y343270D01*
G01Y345537D02*
X842608Y345829D01*
X842733Y346162D01*
X842941Y346370D01*
X843233Y346454D01*
X843524Y346370D01*
X843774Y346120D01*
X843899Y345745D01*
Y345329D01*
X843983Y345079D01*
X844191Y344870D01*
X844483Y344787D01*
X844774Y344912D01*
X844983Y345204D01*
X845066Y345537D01*
X844983Y345870D01*
X844774Y346162D01*
X844483Y346287D01*
X844191Y346204D01*
X843983Y345995D01*
X843899Y345745D01*
Y345329D01*
X843774Y344954D01*
X843524Y344704D01*
X843233Y344620D01*
X842941Y344704D01*
X842733Y344912D01*
X842608Y345245D01*
X842566Y345537D01*
G01X845066Y348637D02*
X844983Y348304D01*
X844774Y348054D01*
X844524Y347887D01*
X844191Y347762D01*
X843816Y347720D01*
X843441Y347762D01*
X843108Y347887D01*
X842858Y348054D01*
X842649Y348304D01*
X842566Y348637D01*
X842649Y348970D01*
X842858Y349220D01*
X843108Y349387D01*
X843441Y349512D01*
X843816Y349554D01*
X844191Y349512D01*
X844524Y349387D01*
X844774Y349220D01*
X844983Y348970D01*
X845066Y348637D01*
G01X842566Y351654D02*
X843108Y351737D01*
X843566Y351862D01*
X843983Y352029D01*
X844441Y352237D01*
X845066Y352570D01*
Y350904D01*
G01X835816Y349814D02*
X839816D01*
Y342414D01*
G01X831516Y343714D02*
X817516D01*
G01X831516Y356714D02*
Y343714D01*
G01X817516D02*
Y356714D01*
G01X834118Y319182D02*
X834451Y319224D01*
X834743Y319390D01*
X834993Y319640D01*
X835160Y319932D01*
X835243Y320265D01*
Y320599D01*
X835160Y320932D01*
X834993Y321224D01*
X834743Y321474D01*
X834451Y321640D01*
X834118Y321682D01*
X833785Y321640D01*
X833493Y321474D01*
X833243Y321224D01*
X833076Y320932D01*
X832993Y320599D01*
Y320265D01*
X833076Y319932D01*
X833243Y319640D01*
X833493Y319390D01*
X833785Y319224D01*
X834118Y319182D01*
G01X833785Y319849D02*
X833285Y319182D01*
G01X831810Y321265D02*
X831560Y321515D01*
X831268Y321640D01*
X830935Y321682D01*
X830518Y321599D01*
X830226Y321390D01*
X830143Y321140D01*
X830185Y320890D01*
X830351Y320682D01*
X831185Y320265D01*
X831560Y319974D01*
X831810Y319557D01*
X831893Y319182D01*
X830143D01*
G01X827918Y321682D02*
X828251Y321599D01*
X828501Y321390D01*
X828668Y321140D01*
X828793Y320807D01*
X828835Y320432D01*
X828793Y320057D01*
X828668Y319724D01*
X828501Y319474D01*
X828251Y319265D01*
X827918Y319182D01*
X827585Y319265D01*
X827335Y319474D01*
X827168Y319724D01*
X827043Y320057D01*
X827001Y320432D01*
X827043Y320807D01*
X827168Y321140D01*
X827335Y321390D01*
X827585Y321599D01*
X827918Y321682D01*
G01X830616Y337794D02*
Y323794D01*
G01X817616Y337794D02*
X830616D01*
G01X817616Y323794D02*
Y337794D01*
G01X830616Y323794D02*
X817616D01*
G01X803825Y419576D02*
X803950Y419326D01*
X804033Y419034D01*
Y418701D01*
X803908Y418326D01*
X803700Y418034D01*
X803450Y417826D01*
X803033Y417659D01*
X802658Y417617D01*
X802283Y417701D01*
X802033Y417826D01*
X801783Y418076D01*
X801616Y418367D01*
X801533Y418659D01*
Y418951D01*
X801616Y419242D01*
X801741Y419492D01*
X801908Y419701D01*
G01X802575Y420967D02*
X802866Y421259D01*
X803033Y421509D01*
X803116Y421842D01*
X803033Y422134D01*
X802866Y422342D01*
X802616Y422509D01*
X802325Y422551D01*
X802075Y422509D01*
X801825Y422342D01*
X801616Y422092D01*
X801533Y421801D01*
X801616Y421467D01*
X801866Y421176D01*
X802241Y421009D01*
X802658Y420967D01*
X803200Y421051D01*
X803491Y421176D01*
X803783Y421384D01*
X803991Y421676D01*
X804033Y421967D01*
X803950Y422259D01*
X803741Y422467D01*
G01X802033Y423942D02*
X801741Y424192D01*
X801575Y424526D01*
X801533Y424901D01*
X801575Y425234D01*
X801783Y425567D01*
X802033Y425776D01*
X802283Y425817D01*
X802575Y425734D01*
X802783Y425442D01*
X802866Y425151D01*
Y424776D01*
G01Y425151D02*
X802991Y425401D01*
X803200Y425609D01*
X803450Y425692D01*
X803700Y425609D01*
X803908Y425401D01*
X804033Y425026D01*
X803991Y424651D01*
X803825Y424276D01*
G01X801533Y427959D02*
X804033D01*
X803533Y427459D01*
G01X801533D02*
Y428459D01*
G01X828692Y385367D02*
X828817Y385117D01*
X828900Y384825D01*
Y384492D01*
X828775Y384117D01*
X828567Y383825D01*
X828317Y383617D01*
X827900Y383450D01*
X827525Y383408D01*
X827150Y383492D01*
X826900Y383617D01*
X826650Y383867D01*
X826483Y384158D01*
X826400Y384450D01*
Y384742D01*
X826483Y385033D01*
X826608Y385283D01*
X826775Y385492D01*
G01X827442Y386758D02*
X827733Y387050D01*
X827900Y387300D01*
X827983Y387633D01*
X827900Y387925D01*
X827733Y388133D01*
X827483Y388300D01*
X827192Y388342D01*
X826942Y388300D01*
X826692Y388133D01*
X826483Y387883D01*
X826400Y387592D01*
X826483Y387258D01*
X826733Y386967D01*
X827108Y386800D01*
X827525Y386758D01*
X828067Y386842D01*
X828358Y386967D01*
X828650Y387175D01*
X828858Y387467D01*
X828900Y387758D01*
X828817Y388050D01*
X828608Y388258D01*
G01X826900Y389733D02*
X826608Y389983D01*
X826442Y390317D01*
X826400Y390692D01*
X826442Y391025D01*
X826650Y391358D01*
X826900Y391567D01*
X827150Y391608D01*
X827442Y391525D01*
X827650Y391233D01*
X827733Y390942D01*
Y390567D01*
G01Y390942D02*
X827858Y391192D01*
X828067Y391400D01*
X828317Y391483D01*
X828567Y391400D01*
X828775Y391192D01*
X828900Y390817D01*
X828858Y390442D01*
X828692Y390067D01*
G01X828483Y392958D02*
X828733Y393208D01*
X828858Y393500D01*
X828900Y393833D01*
X828817Y394250D01*
X828608Y394542D01*
X828358Y394625D01*
X828108Y394583D01*
X827900Y394417D01*
X827483Y393583D01*
X827192Y393208D01*
X826775Y392958D01*
X826400Y392875D01*
Y394625D01*
G01X858418Y397607D02*
X858543Y397357D01*
X858626Y397065D01*
Y396732D01*
X858501Y396357D01*
X858293Y396065D01*
X858043Y395857D01*
X857626Y395690D01*
X857251Y395648D01*
X856876Y395732D01*
X856626Y395857D01*
X856376Y396107D01*
X856209Y396398D01*
X856126Y396690D01*
Y396982D01*
X856209Y397273D01*
X856334Y397523D01*
X856501Y397732D01*
G01X857168Y398998D02*
X857459Y399290D01*
X857626Y399540D01*
X857709Y399873D01*
X857626Y400165D01*
X857459Y400373D01*
X857209Y400540D01*
X856918Y400582D01*
X856668Y400540D01*
X856418Y400373D01*
X856209Y400123D01*
X856126Y399832D01*
X856209Y399498D01*
X856459Y399207D01*
X856834Y399040D01*
X857251Y398998D01*
X857793Y399082D01*
X858084Y399207D01*
X858376Y399415D01*
X858584Y399707D01*
X858626Y399998D01*
X858543Y400290D01*
X858334Y400498D01*
G01X856126Y403390D02*
X858626D01*
X856834Y401848D01*
Y403932D01*
G01X856126Y405907D02*
X856668Y405990D01*
X857126Y406115D01*
X857543Y406282D01*
X858001Y406490D01*
X858626Y406823D01*
Y405157D01*
G01X811097Y352130D02*
X813597D01*
Y353171D01*
X813472Y353505D01*
X813305Y353713D01*
X812972Y353796D01*
X812639Y353713D01*
X812430Y353463D01*
X812305Y353171D01*
Y352130D01*
G01Y353171D02*
X811097Y353796D01*
G01Y356063D02*
X811139Y356355D01*
X811264Y356688D01*
X811472Y356896D01*
X811764Y356980D01*
X812055Y356896D01*
X812305Y356646D01*
X812430Y356271D01*
Y355855D01*
X812514Y355605D01*
X812722Y355396D01*
X813014Y355313D01*
X813305Y355438D01*
X813514Y355730D01*
X813597Y356063D01*
X813514Y356396D01*
X813305Y356688D01*
X813014Y356813D01*
X812722Y356730D01*
X812514Y356521D01*
X812430Y356271D01*
Y355855D01*
X812305Y355480D01*
X812055Y355230D01*
X811764Y355146D01*
X811472Y355230D01*
X811264Y355438D01*
X811139Y355771D01*
X811097Y356063D01*
G01X813597Y359163D02*
X813514Y358830D01*
X813305Y358580D01*
X813055Y358413D01*
X812722Y358288D01*
X812347Y358246D01*
X811972Y358288D01*
X811639Y358413D01*
X811389Y358580D01*
X811180Y358830D01*
X811097Y359163D01*
X811180Y359496D01*
X811389Y359746D01*
X811639Y359913D01*
X811972Y360038D01*
X812347Y360080D01*
X812722Y360038D01*
X813055Y359913D01*
X813305Y359746D01*
X813514Y359496D01*
X813597Y359163D01*
G01X813180Y361471D02*
X813430Y361721D01*
X813555Y362013D01*
X813597Y362346D01*
X813514Y362763D01*
X813305Y363055D01*
X813055Y363138D01*
X812805Y363096D01*
X812597Y362930D01*
X812180Y362096D01*
X811889Y361721D01*
X811472Y361471D01*
X811097Y361388D01*
Y363138D01*
G01X852246Y396594D02*
X854746D01*
Y397635D01*
X854621Y397969D01*
X854454Y398177D01*
X854121Y398260D01*
X853788Y398177D01*
X853579Y397927D01*
X853454Y397635D01*
Y396594D01*
G01Y397635D02*
X852246Y398260D01*
G01Y400527D02*
X852288Y400819D01*
X852413Y401152D01*
X852621Y401360D01*
X852913Y401444D01*
X853204Y401360D01*
X853454Y401110D01*
X853579Y400735D01*
Y400319D01*
X853663Y400069D01*
X853871Y399860D01*
X854163Y399777D01*
X854454Y399902D01*
X854663Y400194D01*
X854746Y400527D01*
X854663Y400860D01*
X854454Y401152D01*
X854163Y401277D01*
X853871Y401194D01*
X853663Y400985D01*
X853579Y400735D01*
Y400319D01*
X853454Y399944D01*
X853204Y399694D01*
X852913Y399610D01*
X852621Y399694D01*
X852413Y399902D01*
X852288Y400235D01*
X852246Y400527D01*
G01Y404127D02*
X854746D01*
X852954Y402585D01*
Y404669D01*
G01X852246Y407227D02*
X854746D01*
X852954Y405685D01*
Y407769D01*
G01X846820Y405472D02*
X850820D01*
Y398072D01*
G01X844854Y421395D02*
Y423895D01*
X843813D01*
X843479Y423770D01*
X843271Y423603D01*
X843188Y423270D01*
X843271Y422937D01*
X843521Y422728D01*
X843813Y422603D01*
X844854D01*
G01X843813D02*
X843188Y421395D01*
G01X840921D02*
X840629Y421437D01*
X840296Y421562D01*
X840088Y421770D01*
X840004Y422062D01*
X840088Y422353D01*
X840338Y422603D01*
X840713Y422728D01*
X841129D01*
X841379Y422812D01*
X841588Y423020D01*
X841671Y423312D01*
X841546Y423603D01*
X841254Y423812D01*
X840921Y423895D01*
X840588Y423812D01*
X840296Y423603D01*
X840171Y423312D01*
X840254Y423020D01*
X840463Y422812D01*
X840713Y422728D01*
X841129D01*
X841504Y422603D01*
X841754Y422353D01*
X841838Y422062D01*
X841754Y421770D01*
X841546Y421562D01*
X841213Y421437D01*
X840921Y421395D01*
G01X837821D02*
Y423895D01*
X838321Y423395D01*
G01Y421395D02*
X837321D01*
G01X834221D02*
Y423895D01*
X835763Y422103D01*
X833679D01*
G01X830500Y424612D02*
Y420612D01*
X823100D01*
G01X834983Y402000D02*
Y404500D01*
X833942D01*
X833608Y404375D01*
X833400Y404208D01*
X833317Y403875D01*
X833400Y403542D01*
X833650Y403333D01*
X833942Y403208D01*
X834983D01*
G01X833942D02*
X833317Y402000D01*
G01X831050D02*
X830758Y402042D01*
X830425Y402167D01*
X830217Y402375D01*
X830133Y402667D01*
X830217Y402958D01*
X830467Y403208D01*
X830842Y403333D01*
X831258D01*
X831508Y403417D01*
X831717Y403625D01*
X831800Y403917D01*
X831675Y404208D01*
X831383Y404417D01*
X831050Y404500D01*
X830717Y404417D01*
X830425Y404208D01*
X830300Y403917D01*
X830383Y403625D01*
X830592Y403417D01*
X830842Y403333D01*
X831258D01*
X831633Y403208D01*
X831883Y402958D01*
X831967Y402667D01*
X831883Y402375D01*
X831675Y402167D01*
X831342Y402042D01*
X831050Y402000D01*
G01X828867Y402500D02*
X828617Y402208D01*
X828283Y402042D01*
X827908Y402000D01*
X827575Y402042D01*
X827242Y402250D01*
X827033Y402500D01*
X826992Y402750D01*
X827075Y403042D01*
X827367Y403250D01*
X827658Y403333D01*
X828033D01*
G01X827658D02*
X827408Y403458D01*
X827200Y403667D01*
X827117Y403917D01*
X827200Y404167D01*
X827408Y404375D01*
X827783Y404500D01*
X828158Y404458D01*
X828533Y404292D01*
G01X825767Y402500D02*
X825517Y402208D01*
X825183Y402042D01*
X824808Y402000D01*
X824475Y402042D01*
X824142Y402250D01*
X823933Y402500D01*
X823892Y402750D01*
X823975Y403042D01*
X824267Y403250D01*
X824558Y403333D01*
X824933D01*
G01X824558D02*
X824308Y403458D01*
X824100Y403667D01*
X824017Y403917D01*
X824100Y404167D01*
X824308Y404375D01*
X824683Y404500D01*
X825058Y404458D01*
X825433Y404292D01*
G01X816881Y405117D02*
Y401117D01*
X809481D01*
G01X830400Y383617D02*
X832900D01*
Y384658D01*
X832775Y384992D01*
X832608Y385200D01*
X832275Y385283D01*
X831942Y385200D01*
X831733Y384950D01*
X831608Y384658D01*
Y383617D01*
G01Y384658D02*
X830400Y385283D01*
G01X830775Y386633D02*
X830567Y386883D01*
X830442Y387175D01*
X830400Y387550D01*
X830483Y387925D01*
X830650Y388217D01*
X830942Y388425D01*
X831275Y388467D01*
X831608Y388383D01*
X831817Y388175D01*
X831983Y387883D01*
X832025Y387592D01*
X831983Y387300D01*
X831817Y386925D01*
X832900Y387050D01*
Y388175D01*
G01X832483Y389858D02*
X832733Y390108D01*
X832858Y390400D01*
X832900Y390733D01*
X832817Y391150D01*
X832608Y391442D01*
X832358Y391525D01*
X832108Y391483D01*
X831900Y391317D01*
X831483Y390483D01*
X831192Y390108D01*
X830775Y389858D01*
X830400Y389775D01*
Y391525D01*
G01X831442Y392958D02*
X831733Y393250D01*
X831900Y393500D01*
X831983Y393833D01*
X831900Y394125D01*
X831733Y394333D01*
X831483Y394500D01*
X831192Y394542D01*
X830942Y394500D01*
X830692Y394333D01*
X830483Y394083D01*
X830400Y393792D01*
X830483Y393458D01*
X830733Y393167D01*
X831108Y393000D01*
X831525Y392958D01*
X832067Y393042D01*
X832358Y393167D01*
X832650Y393375D01*
X832858Y393667D01*
X832900Y393958D01*
X832817Y394250D01*
X832608Y394458D01*
G01X821100Y388200D02*
X817100D01*
Y395600D01*
G01X825600Y360500D02*
X825933Y360542D01*
X826225Y360708D01*
X826475Y360958D01*
X826642Y361250D01*
X826725Y361583D01*
Y361917D01*
X826642Y362250D01*
X826475Y362542D01*
X826225Y362792D01*
X825933Y362958D01*
X825600Y363000D01*
X825267Y362958D01*
X824975Y362792D01*
X824725Y362542D01*
X824558Y362250D01*
X824475Y361917D01*
Y361583D01*
X824558Y361250D01*
X824725Y360958D01*
X824975Y360708D01*
X825267Y360542D01*
X825600Y360500D01*
G01X825267Y361167D02*
X824767Y360500D01*
G01X823292Y362583D02*
X823042Y362833D01*
X822750Y362958D01*
X822417Y363000D01*
X822000Y362917D01*
X821708Y362708D01*
X821625Y362458D01*
X821667Y362208D01*
X821833Y362000D01*
X822667Y361583D01*
X823042Y361292D01*
X823292Y360875D01*
X823375Y360500D01*
X821625D01*
G01X819400D02*
Y363000D01*
X819900Y362500D01*
G01Y360500D02*
X818900D01*
G01X817516Y356714D02*
X831516D01*
G01X855316Y355624D02*
X857816D01*
Y356665D01*
X857691Y356999D01*
X857524Y357207D01*
X857191Y357290D01*
X856858Y357207D01*
X856649Y356957D01*
X856524Y356665D01*
Y355624D01*
G01Y356665D02*
X855316Y357290D01*
G01Y359557D02*
X855358Y359849D01*
X855483Y360182D01*
X855691Y360390D01*
X855983Y360474D01*
X856274Y360390D01*
X856524Y360140D01*
X856649Y359765D01*
Y359349D01*
X856733Y359099D01*
X856941Y358890D01*
X857233Y358807D01*
X857524Y358932D01*
X857733Y359224D01*
X857816Y359557D01*
X857733Y359890D01*
X857524Y360182D01*
X857233Y360307D01*
X856941Y360224D01*
X856733Y360015D01*
X856649Y359765D01*
Y359349D01*
X856524Y358974D01*
X856274Y358724D01*
X855983Y358640D01*
X855691Y358724D01*
X855483Y358932D01*
X855358Y359265D01*
X855316Y359557D01*
G01X855816Y361740D02*
X855524Y361990D01*
X855358Y362324D01*
X855316Y362699D01*
X855358Y363032D01*
X855566Y363365D01*
X855816Y363574D01*
X856066Y363615D01*
X856358Y363532D01*
X856566Y363240D01*
X856649Y362949D01*
Y362574D01*
G01Y362949D02*
X856774Y363199D01*
X856983Y363407D01*
X857233Y363490D01*
X857483Y363407D01*
X857691Y363199D01*
X857816Y362824D01*
X857774Y362449D01*
X857608Y362074D01*
G01X855316Y365674D02*
X855858Y365757D01*
X856316Y365882D01*
X856733Y366049D01*
X857191Y366257D01*
X857816Y366590D01*
Y364924D01*
G01X853536Y377289D02*
X852703D01*
Y376539D01*
X852953Y376289D01*
X853244Y376122D01*
X853661Y376039D01*
X854078Y376122D01*
X854369Y376289D01*
X854619Y376539D01*
X854786Y376831D01*
X854869Y377164D01*
Y377456D01*
X854786Y377706D01*
X854619Y377997D01*
X854369Y378247D01*
X854119Y378414D01*
X853786Y378539D01*
X853494D01*
X853161Y378456D01*
X852911Y378289D01*
G01X850686Y376039D02*
Y378539D01*
X851186Y378039D01*
G01Y376039D02*
X850186D01*
G01X847586Y378539D02*
X847919Y378456D01*
X848169Y378247D01*
X848336Y377997D01*
X848461Y377664D01*
X848503Y377289D01*
X848461Y376914D01*
X848336Y376581D01*
X848169Y376331D01*
X847919Y376122D01*
X847586Y376039D01*
X847253Y376122D01*
X847003Y376331D01*
X846836Y376581D01*
X846711Y376914D01*
X846669Y377289D01*
X846711Y377664D01*
X846836Y377997D01*
X847003Y378247D01*
X847253Y378456D01*
X847586Y378539D01*
G01X832017Y411000D02*
Y409208D01*
X831850Y408833D01*
X831517Y408583D01*
X831100Y408500D01*
X830683Y408583D01*
X830350Y408833D01*
X830183Y409208D01*
Y411000D01*
G01X828000Y408500D02*
X827708Y408542D01*
X827375Y408667D01*
X827167Y408875D01*
X827083Y409167D01*
X827167Y409458D01*
X827417Y409708D01*
X827792Y409833D01*
X828208D01*
X828458Y409917D01*
X828667Y410125D01*
X828750Y410417D01*
X828625Y410708D01*
X828333Y410917D01*
X828000Y411000D01*
X827667Y410917D01*
X827375Y410708D01*
X827250Y410417D01*
X827333Y410125D01*
X827542Y409917D01*
X827792Y409833D01*
X828208D01*
X828583Y409708D01*
X828833Y409458D01*
X828917Y409167D01*
X828833Y408875D01*
X828625Y408667D01*
X828292Y408542D01*
X828000Y408500D01*
G01X825692Y410583D02*
X825442Y410833D01*
X825150Y410958D01*
X824817Y411000D01*
X824400Y410917D01*
X824108Y410708D01*
X824025Y410458D01*
X824067Y410208D01*
X824233Y410000D01*
X825067Y409583D01*
X825442Y409292D01*
X825692Y408875D01*
X825775Y408500D01*
X824025D01*
G01X819788Y418537D02*
X809588D01*
G01X819788Y413937D02*
Y418537D01*
G01X808888Y413937D02*
X819788D01*
G01X808888D02*
Y425237D01*
G01X810088Y416237D02*
X808888Y415037D01*
G01X810088Y416237D02*
X808888Y417437D01*
G01X822342Y434696D02*
Y437196D01*
X821301D01*
X820967Y437071D01*
X820759Y436904D01*
X820676Y436571D01*
X820759Y436238D01*
X821009Y436029D01*
X821301Y435904D01*
X822342D01*
G01X821301D02*
X820676Y434696D01*
G01X818409D02*
X818117Y434738D01*
X817784Y434863D01*
X817576Y435071D01*
X817492Y435363D01*
X817576Y435654D01*
X817826Y435904D01*
X818201Y436029D01*
X818617D01*
X818867Y436113D01*
X819076Y436321D01*
X819159Y436613D01*
X819034Y436904D01*
X818742Y437113D01*
X818409Y437196D01*
X818076Y437113D01*
X817784Y436904D01*
X817659Y436613D01*
X817742Y436321D01*
X817951Y436113D01*
X818201Y436029D01*
X818617D01*
X818992Y435904D01*
X819242Y435654D01*
X819326Y435363D01*
X819242Y435071D01*
X819034Y434863D01*
X818701Y434738D01*
X818409Y434696D01*
G01X815309D02*
Y437196D01*
X815809Y436696D01*
G01Y434696D02*
X814809D01*
G01X813126Y435196D02*
X812876Y434904D01*
X812542Y434738D01*
X812167Y434696D01*
X811834Y434738D01*
X811501Y434946D01*
X811292Y435196D01*
X811251Y435446D01*
X811334Y435738D01*
X811626Y435946D01*
X811917Y436029D01*
X812292D01*
G01X811917D02*
X811667Y436154D01*
X811459Y436363D01*
X811376Y436613D01*
X811459Y436863D01*
X811667Y437071D01*
X812042Y437196D01*
X812417Y437154D01*
X812792Y436988D01*
G01X811496Y426321D02*
Y430321D01*
X818896D01*
G01X794105Y523325D02*
X794230Y523075D01*
X794313Y522783D01*
Y522450D01*
X794188Y522075D01*
X793980Y521783D01*
X793730Y521575D01*
X793313Y521408D01*
X792938Y521366D01*
X792563Y521450D01*
X792313Y521575D01*
X792063Y521825D01*
X791896Y522116D01*
X791813Y522408D01*
Y522700D01*
X791896Y522991D01*
X792021Y523241D01*
X792188Y523450D01*
G01X792855Y524716D02*
X793146Y525008D01*
X793313Y525258D01*
X793396Y525591D01*
X793313Y525883D01*
X793146Y526091D01*
X792896Y526258D01*
X792605Y526300D01*
X792355Y526258D01*
X792105Y526091D01*
X791896Y525841D01*
X791813Y525550D01*
X791896Y525216D01*
X792146Y524925D01*
X792521Y524758D01*
X792938Y524716D01*
X793480Y524800D01*
X793771Y524925D01*
X794063Y525133D01*
X794271Y525425D01*
X794313Y525716D01*
X794230Y526008D01*
X794021Y526216D01*
G01X794313Y528608D02*
X794230Y528275D01*
X794021Y528025D01*
X793771Y527858D01*
X793438Y527733D01*
X793063Y527691D01*
X792688Y527733D01*
X792355Y527858D01*
X792105Y528025D01*
X791896Y528275D01*
X791813Y528608D01*
X791896Y528941D01*
X792105Y529191D01*
X792355Y529358D01*
X792688Y529483D01*
X793063Y529525D01*
X793438Y529483D01*
X793771Y529358D01*
X794021Y529191D01*
X794230Y528941D01*
X794313Y528608D01*
G01X791813Y531625D02*
X792355Y531708D01*
X792813Y531833D01*
X793230Y532000D01*
X793688Y532208D01*
X794313Y532541D01*
Y530875D01*
G01X790105Y523325D02*
X790230Y523075D01*
X790313Y522783D01*
Y522450D01*
X790188Y522075D01*
X789980Y521783D01*
X789730Y521575D01*
X789313Y521408D01*
X788938Y521366D01*
X788563Y521450D01*
X788313Y521575D01*
X788063Y521825D01*
X787896Y522116D01*
X787813Y522408D01*
Y522700D01*
X787896Y522991D01*
X788021Y523241D01*
X788188Y523450D01*
G01X788855Y524716D02*
X789146Y525008D01*
X789313Y525258D01*
X789396Y525591D01*
X789313Y525883D01*
X789146Y526091D01*
X788896Y526258D01*
X788605Y526300D01*
X788355Y526258D01*
X788105Y526091D01*
X787896Y525841D01*
X787813Y525550D01*
X787896Y525216D01*
X788146Y524925D01*
X788521Y524758D01*
X788938Y524716D01*
X789480Y524800D01*
X789771Y524925D01*
X790063Y525133D01*
X790271Y525425D01*
X790313Y525716D01*
X790230Y526008D01*
X790021Y526216D01*
G01X790313Y528608D02*
X790230Y528275D01*
X790021Y528025D01*
X789771Y527858D01*
X789438Y527733D01*
X789063Y527691D01*
X788688Y527733D01*
X788355Y527858D01*
X788105Y528025D01*
X787896Y528275D01*
X787813Y528608D01*
X787896Y528941D01*
X788105Y529191D01*
X788355Y529358D01*
X788688Y529483D01*
X789063Y529525D01*
X789438Y529483D01*
X789771Y529358D01*
X790021Y529191D01*
X790230Y528941D01*
X790313Y528608D01*
G01X787813Y531708D02*
X787855Y532000D01*
X787980Y532333D01*
X788188Y532541D01*
X788480Y532625D01*
X788771Y532541D01*
X789021Y532291D01*
X789146Y531916D01*
Y531500D01*
X789230Y531250D01*
X789438Y531041D01*
X789730Y530958D01*
X790021Y531083D01*
X790230Y531375D01*
X790313Y531708D01*
X790230Y532041D01*
X790021Y532333D01*
X789730Y532458D01*
X789438Y532375D01*
X789230Y532166D01*
X789146Y531916D01*
Y531500D01*
X789021Y531125D01*
X788771Y530875D01*
X788480Y530791D01*
X788188Y530875D01*
X787980Y531083D01*
X787855Y531416D01*
X787813Y531708D01*
G01X798105Y523325D02*
X798230Y523075D01*
X798313Y522783D01*
Y522450D01*
X798188Y522075D01*
X797980Y521783D01*
X797730Y521575D01*
X797313Y521408D01*
X796938Y521366D01*
X796563Y521450D01*
X796313Y521575D01*
X796063Y521825D01*
X795896Y522116D01*
X795813Y522408D01*
Y522700D01*
X795896Y522991D01*
X796021Y523241D01*
X796188Y523450D01*
G01X796855Y524716D02*
X797146Y525008D01*
X797313Y525258D01*
X797396Y525591D01*
X797313Y525883D01*
X797146Y526091D01*
X796896Y526258D01*
X796605Y526300D01*
X796355Y526258D01*
X796105Y526091D01*
X795896Y525841D01*
X795813Y525550D01*
X795896Y525216D01*
X796146Y524925D01*
X796521Y524758D01*
X796938Y524716D01*
X797480Y524800D01*
X797771Y524925D01*
X798063Y525133D01*
X798271Y525425D01*
X798313Y525716D01*
X798230Y526008D01*
X798021Y526216D01*
G01X797896Y527816D02*
X798146Y528066D01*
X798271Y528358D01*
X798313Y528691D01*
X798230Y529108D01*
X798021Y529400D01*
X797771Y529483D01*
X797521Y529441D01*
X797313Y529275D01*
X796896Y528441D01*
X796605Y528066D01*
X796188Y527816D01*
X795813Y527733D01*
Y529483D01*
G01X796105Y531000D02*
X795896Y531291D01*
X795813Y531625D01*
X795896Y531958D01*
X796146Y532250D01*
X796521Y532458D01*
X796896Y532541D01*
X797355D01*
X797730Y532458D01*
X798063Y532250D01*
X798230Y532000D01*
X798313Y531708D01*
X798230Y531375D01*
X798063Y531125D01*
X797813Y530958D01*
X797480Y530875D01*
X797188Y530958D01*
X796896Y531166D01*
X796730Y531416D01*
X796688Y531708D01*
X796771Y532041D01*
X796980Y532291D01*
X797355Y532541D01*
G01X802105Y523325D02*
X802230Y523075D01*
X802313Y522783D01*
Y522450D01*
X802188Y522075D01*
X801980Y521783D01*
X801730Y521575D01*
X801313Y521408D01*
X800938Y521366D01*
X800563Y521450D01*
X800313Y521575D01*
X800063Y521825D01*
X799896Y522116D01*
X799813Y522408D01*
Y522700D01*
X799896Y522991D01*
X800021Y523241D01*
X800188Y523450D01*
G01X800855Y524716D02*
X801146Y525008D01*
X801313Y525258D01*
X801396Y525591D01*
X801313Y525883D01*
X801146Y526091D01*
X800896Y526258D01*
X800605Y526300D01*
X800355Y526258D01*
X800105Y526091D01*
X799896Y525841D01*
X799813Y525550D01*
X799896Y525216D01*
X800146Y524925D01*
X800521Y524758D01*
X800938Y524716D01*
X801480Y524800D01*
X801771Y524925D01*
X802063Y525133D01*
X802271Y525425D01*
X802313Y525716D01*
X802230Y526008D01*
X802021Y526216D01*
G01X802313Y528608D02*
X802230Y528275D01*
X802021Y528025D01*
X801771Y527858D01*
X801438Y527733D01*
X801063Y527691D01*
X800688Y527733D01*
X800355Y527858D01*
X800105Y528025D01*
X799896Y528275D01*
X799813Y528608D01*
X799896Y528941D01*
X800105Y529191D01*
X800355Y529358D01*
X800688Y529483D01*
X801063Y529525D01*
X801438Y529483D01*
X801771Y529358D01*
X802021Y529191D01*
X802230Y528941D01*
X802313Y528608D01*
G01X800855Y530916D02*
X801146Y531208D01*
X801313Y531458D01*
X801396Y531791D01*
X801313Y532083D01*
X801146Y532291D01*
X800896Y532458D01*
X800605Y532500D01*
X800355Y532458D01*
X800105Y532291D01*
X799896Y532041D01*
X799813Y531750D01*
X799896Y531416D01*
X800146Y531125D01*
X800521Y530958D01*
X800938Y530916D01*
X801480Y531000D01*
X801771Y531125D01*
X802063Y531333D01*
X802271Y531625D01*
X802313Y531916D01*
X802230Y532208D01*
X802021Y532416D01*
G01X896086Y191934D02*
X896336Y192059D01*
X896628Y192142D01*
X896961D01*
X897336Y192017D01*
X897628Y191809D01*
X897836Y191559D01*
X898003Y191142D01*
X898045Y190767D01*
X897961Y190392D01*
X897836Y190142D01*
X897586Y189892D01*
X897295Y189725D01*
X897003Y189642D01*
X896711D01*
X896420Y189725D01*
X896170Y189850D01*
X895961Y190017D01*
G01X893903Y189642D02*
Y192142D01*
X894403Y191642D01*
G01Y189642D02*
X893403D01*
G01X891720Y190017D02*
X891470Y189809D01*
X891178Y189684D01*
X890803Y189642D01*
X890428Y189725D01*
X890136Y189892D01*
X889928Y190184D01*
X889886Y190517D01*
X889970Y190850D01*
X890178Y191059D01*
X890470Y191225D01*
X890761Y191267D01*
X891053Y191225D01*
X891428Y191059D01*
X891303Y192142D01*
X890178D01*
G01X888620Y190142D02*
X888370Y189850D01*
X888036Y189684D01*
X887661Y189642D01*
X887328Y189684D01*
X886995Y189892D01*
X886786Y190142D01*
X886745Y190392D01*
X886828Y190684D01*
X887120Y190892D01*
X887411Y190975D01*
X887786D01*
G01X887411D02*
X887161Y191100D01*
X886953Y191309D01*
X886870Y191559D01*
X886953Y191809D01*
X887161Y192017D01*
X887536Y192142D01*
X887911Y192100D01*
X888286Y191934D01*
G01X896086Y195934D02*
X896336Y196059D01*
X896628Y196142D01*
X896961D01*
X897336Y196017D01*
X897628Y195809D01*
X897836Y195559D01*
X898003Y195142D01*
X898045Y194767D01*
X897961Y194392D01*
X897836Y194142D01*
X897586Y193892D01*
X897295Y193725D01*
X897003Y193642D01*
X896711D01*
X896420Y193725D01*
X896170Y193850D01*
X895961Y194017D01*
G01X893903Y193642D02*
Y196142D01*
X894403Y195642D01*
G01Y193642D02*
X893403D01*
G01X891720Y194017D02*
X891470Y193809D01*
X891178Y193684D01*
X890803Y193642D01*
X890428Y193725D01*
X890136Y193892D01*
X889928Y194184D01*
X889886Y194517D01*
X889970Y194850D01*
X890178Y195059D01*
X890470Y195225D01*
X890761Y195267D01*
X891053Y195225D01*
X891428Y195059D01*
X891303Y196142D01*
X890178D01*
G01X887203Y193642D02*
Y196142D01*
X888745Y194350D01*
X886661D01*
G01X880056Y160836D02*
X880306Y160961D01*
X880598Y161044D01*
X880931D01*
X881306Y160919D01*
X881598Y160711D01*
X881806Y160461D01*
X881973Y160044D01*
X882015Y159669D01*
X881931Y159294D01*
X881806Y159044D01*
X881556Y158794D01*
X881265Y158627D01*
X880973Y158544D01*
X880681D01*
X880390Y158627D01*
X880140Y158752D01*
X879931Y158919D01*
G01X877873Y158544D02*
Y161044D01*
X878373Y160544D01*
G01Y158544D02*
X877373D01*
G01X875690Y158919D02*
X875440Y158711D01*
X875148Y158586D01*
X874773Y158544D01*
X874398Y158627D01*
X874106Y158794D01*
X873898Y159086D01*
X873856Y159419D01*
X873940Y159752D01*
X874148Y159961D01*
X874440Y160127D01*
X874731Y160169D01*
X875023Y160127D01*
X875398Y159961D01*
X875273Y161044D01*
X874148D01*
G01X871673Y158544D02*
X871381Y158586D01*
X871048Y158711D01*
X870840Y158919D01*
X870756Y159211D01*
X870840Y159502D01*
X871090Y159752D01*
X871465Y159877D01*
X871881D01*
X872131Y159961D01*
X872340Y160169D01*
X872423Y160461D01*
X872298Y160752D01*
X872006Y160961D01*
X871673Y161044D01*
X871340Y160961D01*
X871048Y160752D01*
X870923Y160461D01*
X871006Y160169D01*
X871215Y159961D01*
X871465Y159877D01*
X871881D01*
X872256Y159752D01*
X872506Y159502D01*
X872590Y159211D01*
X872506Y158919D01*
X872298Y158711D01*
X871965Y158586D01*
X871673Y158544D01*
G01X878983Y226000D02*
Y228500D01*
X877942D01*
X877608Y228375D01*
X877400Y228208D01*
X877317Y227875D01*
X877400Y227542D01*
X877650Y227333D01*
X877942Y227208D01*
X878983D01*
G01X877942D02*
X877317Y226000D01*
G01X874550D02*
Y228500D01*
X876092Y226708D01*
X874008D01*
G01X872742Y227042D02*
X872450Y227333D01*
X872200Y227500D01*
X871867Y227583D01*
X871575Y227500D01*
X871367Y227333D01*
X871200Y227083D01*
X871158Y226792D01*
X871200Y226542D01*
X871367Y226292D01*
X871617Y226083D01*
X871908Y226000D01*
X872242Y226083D01*
X872533Y226333D01*
X872700Y226708D01*
X872742Y227125D01*
X872658Y227667D01*
X872533Y227958D01*
X872325Y228250D01*
X872033Y228458D01*
X871742Y228500D01*
X871450Y228417D01*
X871242Y228208D01*
G01X868350Y226000D02*
Y228500D01*
X869892Y226708D01*
X867808D01*
G01X893445Y216953D02*
X890945D01*
Y218619D01*
G01X891987Y220094D02*
X892278Y220386D01*
X892445Y220636D01*
X892528Y220969D01*
X892445Y221261D01*
X892278Y221469D01*
X892028Y221636D01*
X891737Y221678D01*
X891487Y221636D01*
X891237Y221469D01*
X891028Y221219D01*
X890945Y220928D01*
X891028Y220594D01*
X891278Y220303D01*
X891653Y220136D01*
X892070Y220094D01*
X892612Y220178D01*
X892903Y220303D01*
X893195Y220511D01*
X893403Y220803D01*
X893445Y221094D01*
X893362Y221386D01*
X893153Y221594D01*
G01X881759Y213315D02*
Y226715D01*
G01X888959Y213315D02*
X881759D01*
G01X888959Y226715D02*
Y213315D01*
G01X881759Y226715D02*
X888959D01*
G01X889478Y317532D02*
X889728Y317657D01*
X890020Y317740D01*
X890353D01*
X890728Y317615D01*
X891020Y317407D01*
X891228Y317157D01*
X891395Y316740D01*
X891437Y316365D01*
X891353Y315990D01*
X891228Y315740D01*
X890978Y315490D01*
X890687Y315323D01*
X890395Y315240D01*
X890103D01*
X889812Y315323D01*
X889562Y315448D01*
X889353Y315615D01*
G01X888087Y316282D02*
X887795Y316573D01*
X887545Y316740D01*
X887212Y316823D01*
X886920Y316740D01*
X886712Y316573D01*
X886545Y316323D01*
X886503Y316032D01*
X886545Y315782D01*
X886712Y315532D01*
X886962Y315323D01*
X887253Y315240D01*
X887587Y315323D01*
X887878Y315573D01*
X888045Y315948D01*
X888087Y316365D01*
X888003Y316907D01*
X887878Y317198D01*
X887670Y317490D01*
X887378Y317698D01*
X887087Y317740D01*
X886795Y317657D01*
X886587Y317448D01*
G01X885112Y315740D02*
X884862Y315448D01*
X884528Y315282D01*
X884153Y315240D01*
X883820Y315282D01*
X883487Y315490D01*
X883278Y315740D01*
X883237Y315990D01*
X883320Y316282D01*
X883612Y316490D01*
X883903Y316573D01*
X884278D01*
G01X883903D02*
X883653Y316698D01*
X883445Y316907D01*
X883362Y317157D01*
X883445Y317407D01*
X883653Y317615D01*
X884028Y317740D01*
X884403Y317698D01*
X884778Y317532D01*
G01X881803Y315532D02*
X881512Y315323D01*
X881178Y315240D01*
X880845Y315323D01*
X880553Y315573D01*
X880345Y315948D01*
X880262Y316323D01*
Y316782D01*
X880345Y317157D01*
X880553Y317490D01*
X880803Y317657D01*
X881095Y317740D01*
X881428Y317657D01*
X881678Y317490D01*
X881845Y317240D01*
X881928Y316907D01*
X881845Y316615D01*
X881637Y316323D01*
X881387Y316157D01*
X881095Y316115D01*
X880762Y316198D01*
X880512Y316407D01*
X880262Y316782D01*
G01X880233Y349792D02*
X880483Y349917D01*
X880775Y350000D01*
X881108D01*
X881483Y349875D01*
X881775Y349667D01*
X881983Y349417D01*
X882150Y349000D01*
X882192Y348625D01*
X882108Y348250D01*
X881983Y348000D01*
X881733Y347750D01*
X881442Y347583D01*
X881150Y347500D01*
X880858D01*
X880567Y347583D01*
X880317Y347708D01*
X880108Y347875D01*
G01X878842Y348542D02*
X878550Y348833D01*
X878300Y349000D01*
X877967Y349083D01*
X877675Y349000D01*
X877467Y348833D01*
X877300Y348583D01*
X877258Y348292D01*
X877300Y348042D01*
X877467Y347792D01*
X877717Y347583D01*
X878008Y347500D01*
X878342Y347583D01*
X878633Y347833D01*
X878800Y348208D01*
X878842Y348625D01*
X878758Y349167D01*
X878633Y349458D01*
X878425Y349750D01*
X878133Y349958D01*
X877842Y350000D01*
X877550Y349917D01*
X877342Y349708D01*
G01X875867Y347875D02*
X875617Y347667D01*
X875325Y347542D01*
X874950Y347500D01*
X874575Y347583D01*
X874283Y347750D01*
X874075Y348042D01*
X874033Y348375D01*
X874117Y348708D01*
X874325Y348917D01*
X874617Y349083D01*
X874908Y349125D01*
X875200Y349083D01*
X875575Y348917D01*
X875450Y350000D01*
X874325D01*
G01X872767Y348000D02*
X872517Y347708D01*
X872183Y347542D01*
X871808Y347500D01*
X871475Y347542D01*
X871142Y347750D01*
X870933Y348000D01*
X870892Y348250D01*
X870975Y348542D01*
X871267Y348750D01*
X871558Y348833D01*
X871933D01*
G01X871558D02*
X871308Y348958D01*
X871100Y349167D01*
X871017Y349417D01*
X871100Y349667D01*
X871308Y349875D01*
X871683Y350000D01*
X872058Y349958D01*
X872433Y349792D01*
G01X889478Y333532D02*
X889728Y333657D01*
X890020Y333740D01*
X890353D01*
X890728Y333615D01*
X891020Y333407D01*
X891228Y333157D01*
X891395Y332740D01*
X891437Y332365D01*
X891353Y331990D01*
X891228Y331740D01*
X890978Y331490D01*
X890687Y331323D01*
X890395Y331240D01*
X890103D01*
X889812Y331323D01*
X889562Y331448D01*
X889353Y331615D01*
G01X888087Y332282D02*
X887795Y332573D01*
X887545Y332740D01*
X887212Y332823D01*
X886920Y332740D01*
X886712Y332573D01*
X886545Y332323D01*
X886503Y332032D01*
X886545Y331782D01*
X886712Y331532D01*
X886962Y331323D01*
X887253Y331240D01*
X887587Y331323D01*
X887878Y331573D01*
X888045Y331948D01*
X888087Y332365D01*
X888003Y332907D01*
X887878Y333198D01*
X887670Y333490D01*
X887378Y333698D01*
X887087Y333740D01*
X886795Y333657D01*
X886587Y333448D01*
G01X883695Y331240D02*
Y333740D01*
X885237Y331948D01*
X883153D01*
G01X881095Y333740D02*
X881428Y333657D01*
X881678Y333448D01*
X881845Y333198D01*
X881970Y332865D01*
X882012Y332490D01*
X881970Y332115D01*
X881845Y331782D01*
X881678Y331532D01*
X881428Y331323D01*
X881095Y331240D01*
X880762Y331323D01*
X880512Y331532D01*
X880345Y331782D01*
X880220Y332115D01*
X880178Y332490D01*
X880220Y332865D01*
X880345Y333198D01*
X880512Y333448D01*
X880762Y333657D01*
X881095Y333740D01*
G01X889478Y337532D02*
X889728Y337657D01*
X890020Y337740D01*
X890353D01*
X890728Y337615D01*
X891020Y337407D01*
X891228Y337157D01*
X891395Y336740D01*
X891437Y336365D01*
X891353Y335990D01*
X891228Y335740D01*
X890978Y335490D01*
X890687Y335323D01*
X890395Y335240D01*
X890103D01*
X889812Y335323D01*
X889562Y335448D01*
X889353Y335615D01*
G01X888087Y336282D02*
X887795Y336573D01*
X887545Y336740D01*
X887212Y336823D01*
X886920Y336740D01*
X886712Y336573D01*
X886545Y336323D01*
X886503Y336032D01*
X886545Y335782D01*
X886712Y335532D01*
X886962Y335323D01*
X887253Y335240D01*
X887587Y335323D01*
X887878Y335573D01*
X888045Y335948D01*
X888087Y336365D01*
X888003Y336907D01*
X887878Y337198D01*
X887670Y337490D01*
X887378Y337698D01*
X887087Y337740D01*
X886795Y337657D01*
X886587Y337448D01*
G01X883695Y335240D02*
Y337740D01*
X885237Y335948D01*
X883153D01*
G01X882012Y335740D02*
X881762Y335448D01*
X881428Y335282D01*
X881053Y335240D01*
X880720Y335282D01*
X880387Y335490D01*
X880178Y335740D01*
X880137Y335990D01*
X880220Y336282D01*
X880512Y336490D01*
X880803Y336573D01*
X881178D01*
G01X880803D02*
X880553Y336698D01*
X880345Y336907D01*
X880262Y337157D01*
X880345Y337407D01*
X880553Y337615D01*
X880928Y337740D01*
X881303Y337698D01*
X881678Y337532D01*
G01X889478Y329532D02*
X889728Y329657D01*
X890020Y329740D01*
X890353D01*
X890728Y329615D01*
X891020Y329407D01*
X891228Y329157D01*
X891395Y328740D01*
X891437Y328365D01*
X891353Y327990D01*
X891228Y327740D01*
X890978Y327490D01*
X890687Y327323D01*
X890395Y327240D01*
X890103D01*
X889812Y327323D01*
X889562Y327448D01*
X889353Y327615D01*
G01X888087Y328282D02*
X887795Y328573D01*
X887545Y328740D01*
X887212Y328823D01*
X886920Y328740D01*
X886712Y328573D01*
X886545Y328323D01*
X886503Y328032D01*
X886545Y327782D01*
X886712Y327532D01*
X886962Y327323D01*
X887253Y327240D01*
X887587Y327323D01*
X887878Y327573D01*
X888045Y327948D01*
X888087Y328365D01*
X888003Y328907D01*
X887878Y329198D01*
X887670Y329490D01*
X887378Y329698D01*
X887087Y329740D01*
X886795Y329657D01*
X886587Y329448D01*
G01X885112Y327615D02*
X884862Y327407D01*
X884570Y327282D01*
X884195Y327240D01*
X883820Y327323D01*
X883528Y327490D01*
X883320Y327782D01*
X883278Y328115D01*
X883362Y328448D01*
X883570Y328657D01*
X883862Y328823D01*
X884153Y328865D01*
X884445Y328823D01*
X884820Y328657D01*
X884695Y329740D01*
X883570D01*
G01X881095D02*
X881428Y329657D01*
X881678Y329448D01*
X881845Y329198D01*
X881970Y328865D01*
X882012Y328490D01*
X881970Y328115D01*
X881845Y327782D01*
X881678Y327532D01*
X881428Y327323D01*
X881095Y327240D01*
X880762Y327323D01*
X880512Y327532D01*
X880345Y327782D01*
X880220Y328115D01*
X880178Y328490D01*
X880220Y328865D01*
X880345Y329198D01*
X880512Y329448D01*
X880762Y329657D01*
X881095Y329740D01*
G01X889478Y325532D02*
X889728Y325657D01*
X890020Y325740D01*
X890353D01*
X890728Y325615D01*
X891020Y325407D01*
X891228Y325157D01*
X891395Y324740D01*
X891437Y324365D01*
X891353Y323990D01*
X891228Y323740D01*
X890978Y323490D01*
X890687Y323323D01*
X890395Y323240D01*
X890103D01*
X889812Y323323D01*
X889562Y323448D01*
X889353Y323615D01*
G01X888087Y324282D02*
X887795Y324573D01*
X887545Y324740D01*
X887212Y324823D01*
X886920Y324740D01*
X886712Y324573D01*
X886545Y324323D01*
X886503Y324032D01*
X886545Y323782D01*
X886712Y323532D01*
X886962Y323323D01*
X887253Y323240D01*
X887587Y323323D01*
X887878Y323573D01*
X888045Y323948D01*
X888087Y324365D01*
X888003Y324907D01*
X887878Y325198D01*
X887670Y325490D01*
X887378Y325698D01*
X887087Y325740D01*
X886795Y325657D01*
X886587Y325448D01*
G01X885112Y323615D02*
X884862Y323407D01*
X884570Y323282D01*
X884195Y323240D01*
X883820Y323323D01*
X883528Y323490D01*
X883320Y323782D01*
X883278Y324115D01*
X883362Y324448D01*
X883570Y324657D01*
X883862Y324823D01*
X884153Y324865D01*
X884445Y324823D01*
X884820Y324657D01*
X884695Y325740D01*
X883570D01*
G01X882012Y323615D02*
X881762Y323407D01*
X881470Y323282D01*
X881095Y323240D01*
X880720Y323323D01*
X880428Y323490D01*
X880220Y323782D01*
X880178Y324115D01*
X880262Y324448D01*
X880470Y324657D01*
X880762Y324823D01*
X881053Y324865D01*
X881345Y324823D01*
X881720Y324657D01*
X881595Y325740D01*
X880470D01*
G01X889478Y321532D02*
X889728Y321657D01*
X890020Y321740D01*
X890353D01*
X890728Y321615D01*
X891020Y321407D01*
X891228Y321157D01*
X891395Y320740D01*
X891437Y320365D01*
X891353Y319990D01*
X891228Y319740D01*
X890978Y319490D01*
X890687Y319323D01*
X890395Y319240D01*
X890103D01*
X889812Y319323D01*
X889562Y319448D01*
X889353Y319615D01*
G01X888087Y320282D02*
X887795Y320573D01*
X887545Y320740D01*
X887212Y320823D01*
X886920Y320740D01*
X886712Y320573D01*
X886545Y320323D01*
X886503Y320032D01*
X886545Y319782D01*
X886712Y319532D01*
X886962Y319323D01*
X887253Y319240D01*
X887587Y319323D01*
X887878Y319573D01*
X888045Y319948D01*
X888087Y320365D01*
X888003Y320907D01*
X887878Y321198D01*
X887670Y321490D01*
X887378Y321698D01*
X887087Y321740D01*
X886795Y321657D01*
X886587Y321448D01*
G01X884987Y320282D02*
X884695Y320573D01*
X884445Y320740D01*
X884112Y320823D01*
X883820Y320740D01*
X883612Y320573D01*
X883445Y320323D01*
X883403Y320032D01*
X883445Y319782D01*
X883612Y319532D01*
X883862Y319323D01*
X884153Y319240D01*
X884487Y319323D01*
X884778Y319573D01*
X884945Y319948D01*
X884987Y320365D01*
X884903Y320907D01*
X884778Y321198D01*
X884570Y321490D01*
X884278Y321698D01*
X883987Y321740D01*
X883695Y321657D01*
X883487Y321448D01*
G01X881095Y321740D02*
X881428Y321657D01*
X881678Y321448D01*
X881845Y321198D01*
X881970Y320865D01*
X882012Y320490D01*
X881970Y320115D01*
X881845Y319782D01*
X881678Y319532D01*
X881428Y319323D01*
X881095Y319240D01*
X880762Y319323D01*
X880512Y319532D01*
X880345Y319782D01*
X880220Y320115D01*
X880178Y320490D01*
X880220Y320865D01*
X880345Y321198D01*
X880512Y321448D01*
X880762Y321657D01*
X881095Y321740D01*
G01X885931Y405023D02*
X886181Y405148D01*
X886473Y405231D01*
X886806D01*
X887181Y405106D01*
X887473Y404898D01*
X887681Y404648D01*
X887848Y404231D01*
X887890Y403856D01*
X887806Y403481D01*
X887681Y403231D01*
X887431Y402981D01*
X887140Y402814D01*
X886848Y402731D01*
X886556D01*
X886265Y402814D01*
X886015Y402939D01*
X885806Y403106D01*
G01X884540Y403773D02*
X884248Y404064D01*
X883998Y404231D01*
X883665Y404314D01*
X883373Y404231D01*
X883165Y404064D01*
X882998Y403814D01*
X882956Y403523D01*
X882998Y403273D01*
X883165Y403023D01*
X883415Y402814D01*
X883706Y402731D01*
X884040Y402814D01*
X884331Y403064D01*
X884498Y403439D01*
X884540Y403856D01*
X884456Y404398D01*
X884331Y404689D01*
X884123Y404981D01*
X883831Y405189D01*
X883540Y405231D01*
X883248Y405148D01*
X883040Y404939D01*
G01X881565Y403231D02*
X881315Y402939D01*
X880981Y402773D01*
X880606Y402731D01*
X880273Y402773D01*
X879940Y402981D01*
X879731Y403231D01*
X879690Y403481D01*
X879773Y403773D01*
X880065Y403981D01*
X880356Y404064D01*
X880731D01*
G01X880356D02*
X880106Y404189D01*
X879898Y404398D01*
X879815Y404648D01*
X879898Y404898D01*
X880106Y405106D01*
X880481Y405231D01*
X880856Y405189D01*
X881231Y405023D01*
G01X878465Y403106D02*
X878215Y402898D01*
X877923Y402773D01*
X877548Y402731D01*
X877173Y402814D01*
X876881Y402981D01*
X876673Y403273D01*
X876631Y403606D01*
X876715Y403939D01*
X876923Y404148D01*
X877215Y404314D01*
X877506Y404356D01*
X877798Y404314D01*
X878173Y404148D01*
X878048Y405231D01*
X876923D01*
G01X913454Y397782D02*
X913579Y397532D01*
X913662Y397240D01*
Y396907D01*
X913537Y396532D01*
X913329Y396240D01*
X913079Y396032D01*
X912662Y395865D01*
X912287Y395823D01*
X911912Y395907D01*
X911662Y396032D01*
X911412Y396282D01*
X911245Y396573D01*
X911162Y396865D01*
Y397157D01*
X911245Y397448D01*
X911370Y397698D01*
X911537Y397907D01*
G01X912204Y399173D02*
X912495Y399465D01*
X912662Y399715D01*
X912745Y400048D01*
X912662Y400340D01*
X912495Y400548D01*
X912245Y400715D01*
X911954Y400757D01*
X911704Y400715D01*
X911454Y400548D01*
X911245Y400298D01*
X911162Y400007D01*
X911245Y399673D01*
X911495Y399382D01*
X911870Y399215D01*
X912287Y399173D01*
X912829Y399257D01*
X913120Y399382D01*
X913412Y399590D01*
X913620Y399882D01*
X913662Y400173D01*
X913579Y400465D01*
X913370Y400673D01*
G01X911662Y402148D02*
X911370Y402398D01*
X911204Y402732D01*
X911162Y403107D01*
X911204Y403440D01*
X911412Y403773D01*
X911662Y403982D01*
X911912Y404023D01*
X912204Y403940D01*
X912412Y403648D01*
X912495Y403357D01*
Y402982D01*
G01Y403357D02*
X912620Y403607D01*
X912829Y403815D01*
X913079Y403898D01*
X913329Y403815D01*
X913537Y403607D01*
X913662Y403232D01*
X913620Y402857D01*
X913454Y402482D01*
G01X911162Y406082D02*
X911704Y406165D01*
X912162Y406290D01*
X912579Y406457D01*
X913037Y406665D01*
X913662Y406998D01*
Y405332D01*
G01X909554Y397747D02*
X909679Y397497D01*
X909762Y397205D01*
Y396872D01*
X909637Y396497D01*
X909429Y396205D01*
X909179Y395997D01*
X908762Y395830D01*
X908387Y395788D01*
X908012Y395872D01*
X907762Y395997D01*
X907512Y396247D01*
X907345Y396538D01*
X907262Y396830D01*
Y397122D01*
X907345Y397413D01*
X907470Y397663D01*
X907637Y397872D01*
G01X908304Y399138D02*
X908595Y399430D01*
X908762Y399680D01*
X908845Y400013D01*
X908762Y400305D01*
X908595Y400513D01*
X908345Y400680D01*
X908054Y400722D01*
X907804Y400680D01*
X907554Y400513D01*
X907345Y400263D01*
X907262Y399972D01*
X907345Y399638D01*
X907595Y399347D01*
X907970Y399180D01*
X908387Y399138D01*
X908929Y399222D01*
X909220Y399347D01*
X909512Y399555D01*
X909720Y399847D01*
X909762Y400138D01*
X909679Y400430D01*
X909470Y400638D01*
G01X907762Y402113D02*
X907470Y402363D01*
X907304Y402697D01*
X907262Y403072D01*
X907304Y403405D01*
X907512Y403738D01*
X907762Y403947D01*
X908012Y403988D01*
X908304Y403905D01*
X908512Y403613D01*
X908595Y403322D01*
Y402947D01*
G01Y403322D02*
X908720Y403572D01*
X908929Y403780D01*
X909179Y403863D01*
X909429Y403780D01*
X909637Y403572D01*
X909762Y403197D01*
X909720Y402822D01*
X909554Y402447D01*
G01X907262Y406130D02*
X907304Y406422D01*
X907429Y406755D01*
X907637Y406963D01*
X907929Y407047D01*
X908220Y406963D01*
X908470Y406713D01*
X908595Y406338D01*
Y405922D01*
X908679Y405672D01*
X908887Y405463D01*
X909179Y405380D01*
X909470Y405505D01*
X909679Y405797D01*
X909762Y406130D01*
X909679Y406463D01*
X909470Y406755D01*
X909179Y406880D01*
X908887Y406797D01*
X908679Y406588D01*
X908595Y406338D01*
Y405922D01*
X908470Y405547D01*
X908220Y405297D01*
X907929Y405213D01*
X907637Y405297D01*
X907429Y405505D01*
X907304Y405838D01*
X907262Y406130D01*
G01X891321Y381938D02*
Y384438D01*
X890280D01*
X889946Y384313D01*
X889738Y384146D01*
X889655Y383813D01*
X889738Y383480D01*
X889988Y383271D01*
X890280Y383146D01*
X891321D01*
G01X890280D02*
X889655Y381938D01*
G01X887388D02*
X887096Y381980D01*
X886763Y382105D01*
X886555Y382313D01*
X886471Y382605D01*
X886555Y382896D01*
X886805Y383146D01*
X887180Y383271D01*
X887596D01*
X887846Y383355D01*
X888055Y383563D01*
X888138Y383855D01*
X888013Y384146D01*
X887721Y384355D01*
X887388Y384438D01*
X887055Y384355D01*
X886763Y384146D01*
X886638Y383855D01*
X886721Y383563D01*
X886930Y383355D01*
X887180Y383271D01*
X887596D01*
X887971Y383146D01*
X888221Y382896D01*
X888305Y382605D01*
X888221Y382313D01*
X888013Y382105D01*
X887680Y381980D01*
X887388Y381938D01*
G01X885205Y382438D02*
X884955Y382146D01*
X884621Y381980D01*
X884246Y381938D01*
X883913Y381980D01*
X883580Y382188D01*
X883371Y382438D01*
X883330Y382688D01*
X883413Y382980D01*
X883705Y383188D01*
X883996Y383271D01*
X884371D01*
G01X883996D02*
X883746Y383396D01*
X883538Y383605D01*
X883455Y383855D01*
X883538Y384105D01*
X883746Y384313D01*
X884121Y384438D01*
X884496Y384396D01*
X884871Y384230D01*
G01X881980Y384021D02*
X881730Y384271D01*
X881438Y384396D01*
X881105Y384438D01*
X880688Y384355D01*
X880396Y384146D01*
X880313Y383896D01*
X880355Y383646D01*
X880521Y383438D01*
X881355Y383021D01*
X881730Y382730D01*
X881980Y382313D01*
X882063Y381938D01*
X880313D01*
G54D16*
G01X44668Y569316D02*
Y565316D01*
G01X52050Y582250D02*
Y578250D01*
G01X66350Y579700D02*
X62350D01*
G01X102674Y533824D02*
Y537824D01*
G01X139887Y563291D02*
X143887D01*
G01X131100Y599300D02*
X127100D01*
G01X143189Y598537D02*
X139189D01*
G01X89000Y675300D02*
Y679300D01*
G01X99700Y713000D02*
Y714100D01*
G01Y710300D02*
Y711400D01*
G01X150840Y552335D02*
X146840D01*
G01X155495Y552366D02*
X151495D01*
G01X144567Y563191D02*
X148567D01*
G01X149257Y563223D02*
X153257D01*
G01X201000Y520000D02*
X205000D01*
G01X196000D02*
X200000D01*
G01X206000D02*
X210000D01*
G01X192571Y561210D02*
Y557210D01*
G01X215000Y520000D02*
X211000D01*
G01X142037Y552286D02*
X146037D01*
G01X195230Y574670D02*
X199230D01*
G01X178348Y566251D02*
Y570251D01*
G01X179505Y578591D02*
X183505D01*
G01X189289Y580625D02*
Y584625D01*
G01X199830Y585440D02*
Y581440D01*
G01X158964Y720268D02*
X162964D01*
G01X216000Y520000D02*
X220000D01*
G01X247100Y633000D02*
X243100D01*
G01X289011Y551256D02*
Y555256D01*
G01X356000Y634900D02*
X352000D01*
G01X351200D02*
X347200D01*
G01X334139Y677369D02*
X337139Y680369D01*
G01X334139Y677369D02*
X331139Y680369D01*
G01X327639D02*
X350139D01*
G01X340639Y660869D02*
Y680369D01*
G01X327639Y660869D02*
X340639D01*
G01X327639Y680369D02*
Y660869D01*
G01X379714Y624780D02*
X375714D01*
G01X377600Y601400D02*
X373600D01*
G01X491500Y56500D02*
X495500D01*
G01X444403Y34700D02*
X448403D01*
G01X504500Y56500D02*
X508500D01*
G01X859704Y171044D02*
X858604D01*
G01X862404D02*
X861304D01*
G01X863486Y157490D02*
Y161490D01*
G01X873790Y223373D02*
Y224473D01*
G01Y220673D02*
Y221773D01*
G01X875798Y390733D02*
Y389633D01*
G01Y393433D02*
Y392333D01*
G01X860711Y360163D02*
X859611D01*
G01X863411D02*
X862311D01*
M02*
